%FSTAX23Y23*%
%MOIN*%
%SFA1B1*%

%IPPOS*%
%ADD10C,0.009840*%
%ADD11C,0.015750*%
%ADD12C,0.023620*%
%ADD13C,0.003940*%
%ADD14C,0.010000*%
%ADD15C,0.007870*%
%ADD16C,0.015750*%
%ADD17C,0.006000*%
%ADD18C,0.007000*%
%ADD19C,0.005000*%
%ADD20C,0.005910*%
%ADD21C,0.004720*%
%ADD22C,0.008000*%
%ADD23C,0.007990*%
%ADD24C,0.009000*%
%ADD25R,0.025000X0.010000*%
%LNtimingcard_pcb-1*%
%LPD*%
G36*
X01309Y04041D02*
X01294D01*
X01294Y04041*
X01294Y04041*
X01295Y04041*
X01295Y0404*
X01295Y0404*
X01295Y0404*
X01296Y04039*
X01296Y04039*
Y04039*
X01296Y04039*
X01296Y04039*
X01296Y04038*
X01296Y04038*
X01296Y04038*
X01296Y04038*
X01297Y04037*
X01297Y04037*
X01297Y04037*
X01297Y04036*
X01295*
X01295Y04036*
X01295Y04036*
X01295Y04036*
X01295Y04036*
X01295Y04037*
X01295Y04037*
X01294Y04037*
X01294Y04037*
X01294Y04038*
X01294Y04038*
X01293Y04039*
X01293Y0404*
X01293Y0404*
X01293Y0404*
X01293Y0404*
X01292Y0404*
X01292Y0404*
X01292Y0404*
X01292Y0404*
X01291Y04041*
X01291Y04041*
X01291Y04041*
X0129Y04042*
Y04043*
X01309*
Y04041*
G37*
G36*
Y04026D02*
X01294D01*
X01294Y04026*
X01294Y04026*
X01295Y04026*
X01295Y04025*
X01295Y04025*
X01295Y04025*
X01296Y04024*
X01296Y04024*
Y04024*
X01296Y04024*
X01296Y04024*
X01296Y04023*
X01296Y04023*
X01296Y04023*
X01296Y04023*
X01297Y04023*
X01297Y04022*
X01297Y04022*
X01297Y04021*
X01295*
X01295Y04021*
X01295Y04021*
X01295Y04021*
X01295Y04022*
X01295Y04022*
X01295Y04022*
X01294Y04022*
X01294Y04022*
X01294Y04023*
X01294Y04024*
X01293Y04024*
X01293Y04025*
X01293Y04025*
X01293Y04025*
X01293Y04025*
X01292Y04025*
X01292Y04025*
X01292Y04025*
X01292Y04026*
X01291Y04026*
X01291Y04026*
X01291Y04027*
X0129Y04027*
Y04028*
X01309*
Y04026*
G37*
G36*
Y04015D02*
X01305Y04012D01*
X01305Y04012*
X01305Y04012*
X01305Y04012*
X01305Y04012*
X01305Y04012*
X01305Y04012*
X01304Y04012*
X01304Y04011*
X01303Y04011*
X01303Y04011*
X01303Y0401*
X01303*
X01303Y0401*
X01303Y0401*
X01302Y0401*
X01302Y0401*
X01302Y0401*
X01302Y0401*
X01302Y04009*
X01301Y04009*
X01301Y04009*
X01301Y04009*
X01301Y04009*
X01301Y04009*
X01301Y04009*
X01301Y04008*
X01301Y04008*
X01301Y04008*
Y04008*
X01301Y04008*
X01301Y04008*
X01301Y04008*
Y04007*
X01301Y04007*
X01301Y04007*
Y04004*
X01309*
Y04001*
X0129*
Y0401*
X0129Y0401*
Y0401*
X0129Y04011*
X0129Y04011*
X0129Y04012*
X0129Y04012*
X0129Y04013*
X01291Y04013*
X01291Y04013*
Y04013*
X01291Y04014*
X01291Y04014*
X01291Y04014*
X01291Y04014*
X01291Y04014*
X01291Y04015*
X01292Y04015*
X01292Y04015*
X01292Y04016*
X01293*
X01293Y04016*
X01293Y04016*
X01293Y04016*
X01293Y04016*
X01293Y04016*
X01293Y04016*
X01293Y04016*
X01294Y04016*
X01294Y04016*
X01295Y04016*
X01295Y04016*
X01295*
X01295*
X01296*
X01296Y04016*
X01296Y04016*
X01296Y04016*
X01296Y04016*
X01297Y04016*
X01297Y04016*
X01297Y04016*
X01298Y04016*
X01298Y04016*
X01298Y04016*
X01299Y04015*
X01299Y04015*
X01299Y04015*
X01299Y04015*
X01299Y04015*
X01299Y04015*
X01299Y04015*
X01299Y04015*
X01299Y04014*
X013Y04014*
X013Y04014*
X013Y04014*
X013Y04013*
X013Y04013*
X013Y04012*
X013Y04012*
X01301Y04011*
X01301Y04011*
Y04011*
X01301Y04011*
X01301Y04011*
X01301Y04011*
X01301Y04012*
X01301Y04012*
X01301Y04012*
X01301Y04012*
X01302Y04013*
X01302Y04013*
X01302Y04013*
X01302Y04013*
X01302Y04013*
X01302Y04013*
X01302Y04013*
X01302Y04013*
X01303Y04014*
X01303Y04014*
X01304Y04014*
X01304Y04015*
X01309Y04018*
Y04015*
G37*
G36*
X01298Y04157D02*
X01298Y04157D01*
X01298Y04157*
X01299Y04157*
X01299Y04157*
X013Y04157*
X013Y04157*
X01301Y04157*
X01302Y04157*
X01302Y04157*
X01302*
X01302Y04156*
X01302Y04156*
X01303Y04156*
X01303Y04156*
X01303Y04156*
X01303Y04156*
X01303Y04156*
X01304Y04156*
X01304Y04155*
X01305Y04155*
X01305Y04155*
X01305Y04154*
X01305Y04154*
X01305Y04154*
X01306Y04154*
X01306Y04154*
X01306Y04154*
X01306Y04154*
X01306Y04154*
X01306Y04154*
X01306Y04153*
X01306Y04153*
X01306Y04153*
X01306Y04152*
X01306Y04152*
X01306Y04152*
X01307Y04151*
X01307Y04151*
Y04151*
X01307Y04151*
X01306Y04151*
X01306Y0415*
X01306Y0415*
X01306Y0415*
X01306Y04149*
X01306Y04149*
X01306Y04149*
X01306Y04148*
X01306Y04148*
X01305Y04148*
X01305Y04147*
X01305Y04147*
X01305Y04147*
X01305Y04147*
X01304Y04147*
X01304Y04146*
X01304Y04146*
X01304Y04146*
X01304Y04146*
X01303Y04146*
X01303Y04146*
X01302Y04146*
X01302Y04145*
X01301Y04145*
X013Y04145*
X01299Y04145*
X01299Y04145*
X01298Y04145*
X01297Y04145*
X01297*
X01297*
X01296*
X01296Y04145*
X01296*
X01296Y04145*
X01295Y04145*
X01295Y04145*
X01294Y04145*
X01294Y04145*
X01293Y04145*
X01292Y04145*
X01292Y04145*
X01291Y04145*
X01291*
X01291Y04145*
X01291Y04146*
X01291Y04146*
X01291Y04146*
X01291Y04146*
X0129Y04146*
X0129Y04146*
X0129Y04146*
X01289Y04147*
X01289Y04147*
X01288Y04147*
X01288Y04148*
X01288Y04148*
X01288Y04148*
X01288Y04148*
X01288Y04148*
X01288Y04148*
X01288Y04148*
X01288Y04148*
X01288Y04148*
X01287Y04149*
X01287Y04149*
X01287Y04149*
X01287Y0415*
X01287Y0415*
X01287Y0415*
X01287Y04151*
X01287Y04151*
Y04151*
X01287Y04151*
X01287Y04152*
X01287Y04152*
X01287Y04152*
X01287Y04153*
X01287Y04153*
X01288Y04154*
Y04154*
X01288Y04154*
X01288Y04154*
X01288Y04154*
X01288Y04154*
X01288Y04154*
X01288Y04155*
X01289Y04155*
X01289Y04155*
X01289Y04156*
X01289*
X01289Y04156*
X0129Y04156*
X0129Y04156*
X0129Y04156*
X0129Y04156*
X0129Y04156*
X0129Y04156*
X01291Y04156*
X01291Y04156*
X01292Y04157*
X01292Y04157*
X01292*
X01292Y04157*
X01292Y04157*
X01293Y04157*
X01293Y04157*
X01293Y04157*
X01293Y04157*
X01293Y04157*
X01294Y04157*
X01294Y04157*
X01294Y04157*
X01295Y04157*
X01295Y04157*
X01296Y04157*
X01296Y04157*
X01297*
X01297*
X01297*
X01297*
X01297*
X01298Y04157*
G37*
G36*
X01306Y04136D02*
X01291D01*
X01291Y04136*
X01291Y04136*
X01292Y04136*
X01292Y04136*
X01292Y04135*
X01292Y04135*
X01293Y04135*
X01293Y04134*
Y04134*
X01293Y04134*
X01293Y04134*
X01293Y04134*
X01293Y04134*
X01293Y04134*
X01293Y04133*
X01293Y04133*
X01294Y04132*
X01294Y04132*
X01294Y04132*
X01292*
X01292Y04132*
X01292Y04132*
X01292Y04132*
X01292Y04132*
X01292Y04132*
X01291Y04132*
X01291Y04133*
X01291Y04133*
X01291Y04133*
X0129Y04134*
X0129Y04135*
X0129Y04135*
X0129Y04135*
X01289Y04135*
X01289Y04135*
X01289Y04135*
X01289Y04135*
X01289Y04136*
X01289Y04136*
X01288Y04136*
X01288Y04137*
X01287Y04137*
X01287Y04137*
Y04139*
X01306*
Y04136*
G37*
G36*
Y04125D02*
X01302Y04123D01*
X01302Y04123*
X01302Y04123*
X01302Y04123*
X01302Y04122*
X01302Y04122*
X01302Y04122*
X01301Y04122*
X01301Y04122*
X013Y04121*
X013Y04121*
X013Y04121*
X013*
X013Y04121*
X01299Y04121*
X01299Y04121*
X01299Y0412*
X01299Y0412*
X01299Y0412*
X01298Y0412*
X01298Y04119*
X01298Y04119*
X01298Y04119*
X01298Y04119*
X01298Y04119*
X01298Y04119*
X01298Y04119*
X01298Y04119*
X01298Y04118*
Y04118*
X01298Y04118*
X01298Y04118*
X01298Y04118*
Y04118*
X01298Y04118*
X01298Y04117*
Y04114*
X01306*
Y04111*
X01287*
Y0412*
X01287Y04121*
Y04121*
X01287Y04121*
X01287Y04121*
X01287Y04122*
X01287Y04123*
X01287Y04123*
X01287Y04124*
X01288Y04124*
Y04124*
X01288Y04124*
X01288Y04124*
X01288Y04124*
X01288Y04124*
X01288Y04125*
X01288Y04125*
X01289Y04125*
X01289Y04126*
X01289Y04126*
X01289*
X01289Y04126*
X01289Y04126*
X0129Y04126*
X0129Y04126*
X0129Y04126*
X0129Y04126*
X0129Y04126*
X01291Y04127*
X01291Y04127*
X01292Y04127*
X01292Y04127*
X01292*
X01292*
X01292*
X01293Y04127*
X01293Y04127*
X01293Y04127*
X01293Y04127*
X01293Y04127*
X01294Y04126*
X01294Y04126*
X01295Y04126*
X01295Y04126*
X01295Y04126*
X01295Y04126*
X01296Y04125*
X01296Y04125*
X01296Y04125*
X01296Y04125*
X01296Y04125*
X01296Y04125*
X01296Y04125*
X01296Y04125*
X01296Y04124*
X01297Y04124*
X01297Y04124*
X01297Y04124*
X01297Y04123*
X01297Y04123*
X01297Y04122*
X01297Y04122*
X01297Y04121*
Y04121*
X01298Y04121*
X01298Y04122*
X01298Y04122*
X01298Y04122*
X01298Y04122*
X01298Y04122*
X01298Y04123*
X01298Y04123*
X01298Y04123*
X01298Y04123*
X01299Y04123*
X01299Y04123*
X01299Y04123*
X01299Y04123*
X01299Y04124*
X013Y04124*
X013Y04124*
X013Y04125*
X01301Y04125*
X01306Y04128*
Y04125*
G37*
%LNtimingcard_pcb-2*%
%LPC*%
G36*
X01295Y04014D02*
X01295D01*
X01295*
X01295*
X01295Y04014*
X01295*
X01295Y04014*
X01295Y04014*
X01294Y04014*
X01294Y04013*
X01294Y04013*
X01293Y04013*
X01293Y04013*
X01293Y04013*
X01293Y04013*
X01293Y04013*
X01293Y04013*
X01293Y04013*
X01293Y04012*
X01293Y04012*
X01293Y04012*
X01293Y04012*
X01293Y04012*
X01292Y04011*
X01292Y04011*
X01292Y04011*
X01292Y0401*
X01292Y0401*
Y04004*
X01299*
Y04009*
X01299Y04009*
Y0401*
X01299Y0401*
X01299Y0401*
X01298Y04011*
X01298Y04011*
X01298Y04012*
Y04012*
X01298Y04012*
X01298Y04012*
X01298Y04012*
X01298Y04012*
X01298Y04013*
X01298Y04013*
X01297Y04013*
X01297Y04013*
X01297Y04013*
X01297Y04013*
X01297Y04013*
X01297Y04014*
X01296Y04014*
X01296Y04014*
X01296Y04014*
X01295Y04014*
G37*
G36*
X01297Y04155D02*
X01297D01*
X01297*
X01297*
X01297*
X01296*
X01296*
X01296Y04155*
X01296Y04155*
X01295Y04155*
X01295Y04155*
X01294Y04155*
X01293Y04155*
X01293Y04154*
X01292Y04154*
X01292Y04154*
X01291Y04154*
X01291Y04154*
X0129Y04154*
X0129Y04154*
X0129Y04154*
X0129Y04154*
X0129Y04154*
X0129Y04153*
X0129Y04153*
X0129Y04153*
X0129Y04153*
X01289Y04153*
X01289Y04152*
X01289Y04152*
X01289Y04152*
X01289Y04151*
X01289Y04151*
Y04151*
X01289Y04151*
X01289Y04151*
X01289Y0415*
X01289Y0415*
X01289Y0415*
X01289Y04149*
X01289Y04149*
X0129Y04149*
X0129Y04149*
X0129Y04149*
X0129Y04148*
X0129Y04148*
X0129Y04148*
X0129Y04148*
X01291Y04148*
X01291Y04148*
X01291Y04148*
X01291Y04148*
X01292Y04148*
X01292Y04148*
X01293Y04148*
X01293Y04147*
X01294Y04147*
X01294Y04147*
X01295Y04147*
X01296Y04147*
X01297Y04147*
X01297*
X01297*
X01297*
X01297*
X01297*
X01297*
X01298Y04147*
X01298Y04147*
X01298Y04147*
X01299Y04147*
X01299Y04147*
X013Y04147*
X01301Y04148*
X01301Y04148*
X01302Y04148*
X01302Y04148*
X01303Y04148*
X01303Y04148*
X01303Y04148*
X01303Y04148*
X01303Y04148*
X01303Y04148*
X01303Y04149*
X01304Y04149*
X01304Y04149*
X01304Y04149*
X01304Y0415*
X01304Y0415*
X01305Y0415*
X01305Y04151*
X01305Y04151*
Y04151*
X01305Y04151*
Y04151*
X01305Y04151*
X01305Y04152*
X01304Y04152*
X01304Y04152*
X01304Y04152*
X01304Y04153*
X01304Y04153*
X01304Y04153*
X01304Y04153*
X01303Y04154*
X01303Y04154*
X01303Y04154*
X01303Y04154*
X01303Y04154*
X01303Y04154*
X01303Y04154*
X01302Y04154*
X01302Y04154*
X01302Y04154*
X01301Y04154*
X01301Y04154*
X013Y04155*
X013Y04155*
X01299Y04155*
X01298Y04155*
X01298Y04155*
X01297Y04155*
G37*
G36*
X01292Y04124D02*
X01292D01*
X01292*
X01292*
X01292Y04124*
X01292*
X01292Y04124*
X01291Y04124*
X01291Y04124*
X01291Y04124*
X0129Y04124*
X0129Y04123*
X0129Y04123*
X0129Y04123*
X0129Y04123*
X0129Y04123*
X0129Y04123*
X0129Y04123*
X0129Y04123*
X0129Y04123*
X0129Y04122*
X01289Y04122*
X01289Y04122*
X01289Y04122*
X01289Y04121*
X01289Y04121*
X01289Y04121*
X01289Y0412*
Y04114*
X01295*
Y0412*
X01295Y0412*
Y0412*
X01295Y0412*
X01295Y04121*
X01295Y04121*
X01295Y04122*
X01295Y04122*
Y04122*
X01295Y04122*
X01295Y04122*
X01295Y04122*
X01295Y04123*
X01295Y04123*
X01295Y04123*
X01294Y04123*
X01294Y04124*
X01294Y04124*
X01294Y04124*
X01294Y04124*
X01293Y04124*
X01293Y04124*
X01293Y04124*
X01293Y04124*
X01292Y04124*
G37*
%LNtimingcard_pcb-3*%
%LPD*%
G54D10*
X00723Y01882D02*
D01*
X00723Y01883*
X00723Y01883*
X00723Y01883*
X00723Y01884*
X00723Y01884*
X00722Y01884*
X00722Y01885*
X00722Y01885*
X00722Y01885*
X00722Y01885*
X00722Y01886*
X00721Y01886*
X00721Y01886*
X00721Y01886*
X0072Y01887*
X0072Y01887*
X0072Y01887*
X0072Y01887*
X00719Y01887*
X00719Y01887*
X00719Y01887*
X00718Y01887*
X00718*
X00717Y01887*
X00717Y01887*
X00717Y01887*
X00716Y01887*
X00716Y01887*
X00716Y01887*
X00716Y01887*
X00715Y01886*
X00715Y01886*
X00715Y01886*
X00714Y01886*
X00714Y01885*
X00714Y01885*
X00714Y01885*
X00714Y01885*
X00714Y01884*
X00713Y01884*
X00713Y01884*
X00713Y01883*
X00713Y01883*
X00713Y01883*
X00713Y01882*
X00713Y01882*
X00713Y01882*
X00713Y01881*
X00713Y01881*
X00713Y01881*
X00714Y0188*
X00714Y0188*
X00714Y0188*
X00714Y01879*
X00714Y01879*
X00714Y01879*
X00715Y01879*
X00715Y01878*
X00715Y01878*
X00716Y01878*
X00716Y01878*
X00716Y01878*
X00716Y01878*
X00717Y01877*
X00717Y01877*
X00717Y01877*
X00718Y01877*
X00718*
X00719Y01877*
X00719Y01877*
X00719Y01877*
X0072Y01878*
X0072Y01878*
X0072Y01878*
X0072Y01878*
X00721Y01878*
X00721Y01878*
X00721Y01879*
X00722Y01879*
X00722Y01879*
X00722Y01879*
X00722Y0188*
X00722Y0188*
X00722Y0188*
X00723Y01881*
X00723Y01881*
X00723Y01881*
X00723Y01882*
X00723Y01882*
X00723Y01882*
Y0241D02*
D01*
X00723Y0241*
X00723Y02411*
X00723Y02411*
X00723Y02411*
X00723Y02412*
X00722Y02412*
X00722Y02412*
X00722Y02412*
X00722Y02413*
X00722Y02413*
X00722Y02413*
X00721Y02413*
X00721Y02414*
X00721Y02414*
X0072Y02414*
X0072Y02414*
X0072Y02414*
X0072Y02414*
X00719Y02415*
X00719Y02415*
X00719Y02415*
X00718Y02415*
X00718*
X00717Y02415*
X00717Y02415*
X00717Y02415*
X00716Y02414*
X00716Y02414*
X00716Y02414*
X00716Y02414*
X00715Y02414*
X00715Y02414*
X00715Y02413*
X00714Y02413*
X00714Y02413*
X00714Y02413*
X00714Y02412*
X00714Y02412*
X00714Y02412*
X00713Y02412*
X00713Y02411*
X00713Y02411*
X00713Y02411*
X00713Y0241*
X00713Y0241*
X00713Y02409*
X00713Y02409*
X00713Y02409*
X00713Y02408*
X00713Y02408*
X00714Y02408*
X00714Y02408*
X00714Y02407*
X00714Y02407*
X00714Y02407*
X00714Y02406*
X00715Y02406*
X00715Y02406*
X00715Y02406*
X00716Y02406*
X00716Y02405*
X00716Y02405*
X00716Y02405*
X00717Y02405*
X00717Y02405*
X00717Y02405*
X00718Y02405*
X00718*
X00719Y02405*
X00719Y02405*
X00719Y02405*
X0072Y02405*
X0072Y02405*
X0072Y02405*
X0072Y02406*
X00721Y02406*
X00721Y02406*
X00721Y02406*
X00722Y02406*
X00722Y02407*
X00722Y02407*
X00722Y02407*
X00722Y02408*
X00722Y02408*
X00723Y02408*
X00723Y02408*
X00723Y02409*
X00723Y02409*
X00723Y02409*
X00723Y0241*
Y00835D02*
D01*
X00723Y00835*
X00723Y00836*
X00723Y00836*
X00723Y00836*
X00723Y00837*
X00722Y00837*
X00722Y00837*
X00722Y00838*
X00722Y00838*
X00722Y00838*
X00722Y00838*
X00721Y00839*
X00721Y00839*
X00721Y00839*
X0072Y00839*
X0072Y00839*
X0072Y0084*
X0072Y0084*
X00719Y0084*
X00719Y0084*
X00719Y0084*
X00718Y0084*
X00718*
X00717Y0084*
X00717Y0084*
X00717Y0084*
X00716Y0084*
X00716Y0084*
X00716Y00839*
X00716Y00839*
X00715Y00839*
X00715Y00839*
X00715Y00839*
X00714Y00838*
X00714Y00838*
X00714Y00838*
X00714Y00838*
X00714Y00837*
X00714Y00837*
X00713Y00837*
X00713Y00836*
X00713Y00836*
X00713Y00836*
X00713Y00835*
X00713Y00835*
X00713Y00835*
X00713Y00834*
X00713Y00834*
X00713Y00834*
X00713Y00833*
X00714Y00833*
X00714Y00833*
X00714Y00832*
X00714Y00832*
X00714Y00832*
X00714Y00832*
X00715Y00831*
X00715Y00831*
X00715Y00831*
X00716Y00831*
X00716Y00831*
X00716Y0083*
X00716Y0083*
X00717Y0083*
X00717Y0083*
X00717Y0083*
X00718Y0083*
X00718*
X00719Y0083*
X00719Y0083*
X00719Y0083*
X0072Y0083*
X0072Y0083*
X0072Y00831*
X0072Y00831*
X00721Y00831*
X00721Y00831*
X00721Y00831*
X00722Y00832*
X00722Y00832*
X00722Y00832*
X00722Y00832*
X00722Y00833*
X00722Y00833*
X00723Y00833*
X00723Y00834*
X00723Y00834*
X00723Y00834*
X00723Y00835*
X00723Y00835*
Y01363D02*
D01*
X00723Y01363*
X00723Y01363*
X00723Y01364*
X00723Y01364*
X00723Y01364*
X00722Y01365*
X00722Y01365*
X00722Y01365*
X00722Y01365*
X00722Y01366*
X00722Y01366*
X00721Y01366*
X00721Y01366*
X00721Y01367*
X0072Y01367*
X0072Y01367*
X0072Y01367*
X0072Y01367*
X00719Y01367*
X00719Y01367*
X00719Y01367*
X00718Y01367*
X00718*
X00717Y01367*
X00717Y01367*
X00717Y01367*
X00716Y01367*
X00716Y01367*
X00716Y01367*
X00716Y01367*
X00715Y01367*
X00715Y01366*
X00715Y01366*
X00714Y01366*
X00714Y01366*
X00714Y01365*
X00714Y01365*
X00714Y01365*
X00714Y01365*
X00713Y01364*
X00713Y01364*
X00713Y01364*
X00713Y01363*
X00713Y01363*
X00713Y01363*
X00713Y01362*
X00713Y01362*
X00713Y01362*
X00713Y01361*
X00713Y01361*
X00714Y01361*
X00714Y0136*
X00714Y0136*
X00714Y0136*
X00714Y01359*
X00714Y01359*
X00715Y01359*
X00715Y01359*
X00715Y01358*
X00716Y01358*
X00716Y01358*
X00716Y01358*
X00716Y01358*
X00717Y01358*
X00717Y01358*
X00717Y01358*
X00718Y01358*
X00718*
X00719Y01358*
X00719Y01358*
X00719Y01358*
X0072Y01358*
X0072Y01358*
X0072Y01358*
X0072Y01358*
X00721Y01358*
X00721Y01359*
X00721Y01359*
X00722Y01359*
X00722Y01359*
X00722Y0136*
X00722Y0136*
X00722Y0136*
X00722Y01361*
X00723Y01361*
X00723Y01361*
X00723Y01362*
X00723Y01362*
X00723Y01362*
X00723Y01363*
X0438Y03731D02*
D01*
X0438Y03732*
X0438Y03732*
X0438Y03732*
X0438Y03733*
X0438Y03733*
X0438Y03733*
X0438Y03734*
X0438Y03734*
X04379Y03734*
X04379Y03735*
X04379Y03735*
X04379Y03735*
X04379Y03735*
X04378Y03735*
X04378Y03736*
X04378Y03736*
X04377Y03736*
X04377Y03736*
X04377Y03736*
X04376Y03736*
X04376Y03736*
X04376Y03736*
X04375*
X04375Y03736*
X04375Y03736*
X04374Y03736*
X04374Y03736*
X04374Y03736*
X04373Y03736*
X04373Y03736*
X04373Y03735*
X04372Y03735*
X04372Y03735*
X04372Y03735*
X04372Y03735*
X04372Y03734*
X04371Y03734*
X04371Y03734*
X04371Y03733*
X04371Y03733*
X04371Y03733*
X04371Y03732*
X04371Y03732*
X04371Y03732*
X04371Y03731*
X04371Y03731*
X04371Y03731*
X04371Y0373*
X04371Y0373*
X04371Y0373*
X04371Y03729*
X04371Y03729*
X04371Y03729*
X04372Y03728*
X04372Y03728*
X04372Y03728*
X04372Y03728*
X04372Y03728*
X04373Y03727*
X04373Y03727*
X04373Y03727*
X04374Y03727*
X04374Y03727*
X04374Y03727*
X04375Y03727*
X04375Y03726*
X04375Y03726*
X04376*
X04376Y03726*
X04376Y03727*
X04377Y03727*
X04377Y03727*
X04377Y03727*
X04378Y03727*
X04378Y03727*
X04378Y03727*
X04379Y03728*
X04379Y03728*
X04379Y03728*
X04379Y03728*
X04379Y03728*
X0438Y03729*
X0438Y03729*
X0438Y03729*
X0438Y0373*
X0438Y0373*
X0438Y0373*
X0438Y03731*
X0438Y03731*
X0438Y03731*
X02761Y0332D02*
D01*
X02761Y03321*
X02761Y03321*
X02761Y03321*
X02761Y03322*
X02761Y03322*
X02761Y03322*
X02761Y03322*
X02761Y03323*
X0276Y03323*
X0276Y03323*
X0276Y03324*
X0276Y03324*
X02759Y03324*
X02759Y03324*
X02759Y03324*
X02759Y03325*
X02758Y03325*
X02758Y03325*
X02758Y03325*
X02757Y03325*
X02757Y03325*
X02757Y03325*
X02756*
X02756Y03325*
X02756Y03325*
X02755Y03325*
X02755Y03325*
X02755Y03325*
X02754Y03325*
X02754Y03324*
X02754Y03324*
X02753Y03324*
X02753Y03324*
X02753Y03324*
X02753Y03323*
X02752Y03323*
X02752Y03323*
X02752Y03322*
X02752Y03322*
X02752Y03322*
X02752Y03322*
X02752Y03321*
X02752Y03321*
X02751Y03321*
X02751Y0332*
X02751Y0332*
X02752Y03319*
X02752Y03319*
X02752Y03319*
X02752Y03318*
X02752Y03318*
X02752Y03318*
X02752Y03318*
X02752Y03317*
X02753Y03317*
X02753Y03317*
X02753Y03317*
X02753Y03316*
X02754Y03316*
X02754Y03316*
X02754Y03316*
X02755Y03316*
X02755Y03315*
X02755Y03315*
X02756Y03315*
X02756Y03315*
X02756Y03315*
X02757*
X02757Y03315*
X02757Y03315*
X02758Y03315*
X02758Y03315*
X02758Y03316*
X02759Y03316*
X02759Y03316*
X02759Y03316*
X02759Y03316*
X0276Y03317*
X0276Y03317*
X0276Y03317*
X0276Y03317*
X02761Y03318*
X02761Y03318*
X02761Y03318*
X02761Y03318*
X02761Y03319*
X02761Y03319*
X02761Y03319*
X02761Y0332*
X02761Y0332*
X03531Y0375D02*
D01*
X03531Y0375*
X03531Y03751*
X03531Y03751*
X03531Y03751*
X03531Y03752*
X03531Y03752*
X03531Y03752*
X03531Y03752*
X0353Y03753*
X0353Y03753*
X0353Y03753*
X0353Y03754*
X03529Y03754*
X03529Y03754*
X03529Y03754*
X03529Y03754*
X03528Y03754*
X03528Y03755*
X03528Y03755*
X03527Y03755*
X03527Y03755*
X03527Y03755*
X03526*
X03526Y03755*
X03526Y03755*
X03525Y03755*
X03525Y03755*
X03525Y03754*
X03524Y03754*
X03524Y03754*
X03524Y03754*
X03523Y03754*
X03523Y03754*
X03523Y03753*
X03523Y03753*
X03522Y03753*
X03522Y03752*
X03522Y03752*
X03522Y03752*
X03522Y03752*
X03522Y03751*
X03522Y03751*
X03522Y03751*
X03522Y0375*
X03522Y0375*
X03522Y0375*
X03522Y03749*
X03522Y03749*
X03522Y03748*
X03522Y03748*
X03522Y03748*
X03522Y03748*
X03522Y03747*
X03522Y03747*
X03523Y03747*
X03523Y03746*
X03523Y03746*
X03523Y03746*
X03524Y03746*
X03524Y03746*
X03524Y03745*
X03525Y03745*
X03525Y03745*
X03525Y03745*
X03526Y03745*
X03526Y03745*
X03526Y03745*
X03527*
X03527Y03745*
X03527Y03745*
X03528Y03745*
X03528Y03745*
X03528Y03745*
X03529Y03745*
X03529Y03746*
X03529Y03746*
X03529Y03746*
X0353Y03746*
X0353Y03746*
X0353Y03747*
X0353Y03747*
X03531Y03747*
X03531Y03748*
X03531Y03748*
X03531Y03748*
X03531Y03748*
X03531Y03749*
X03531Y03749*
X03531Y0375*
X03531Y0375*
X01636Y0423D02*
D01*
X01636Y0423*
X01636Y0423*
X01636Y04231*
X01636Y04231*
X01636Y04231*
X01636Y04232*
X01635Y04232*
X01635Y04232*
X01635Y04232*
X01635Y04233*
X01635Y04233*
X01634Y04233*
X01634Y04233*
X01634Y04234*
X01634Y04234*
X01633Y04234*
X01633Y04234*
X01633Y04234*
X01632Y04234*
X01632Y04234*
X01632Y04234*
X01631Y04234*
X01631*
X01631Y04234*
X0163Y04234*
X0163Y04234*
X0163Y04234*
X01629Y04234*
X01629Y04234*
X01629Y04234*
X01628Y04234*
X01628Y04233*
X01628Y04233*
X01628Y04233*
X01627Y04233*
X01627Y04232*
X01627Y04232*
X01627Y04232*
X01627Y04232*
X01626Y04231*
X01626Y04231*
X01626Y04231*
X01626Y0423*
X01626Y0423*
X01626Y0423*
X01626Y04229*
X01626Y04229*
X01626Y04229*
X01626Y04228*
X01626Y04228*
X01627Y04228*
X01627Y04227*
X01627Y04227*
X01627Y04227*
X01627Y04226*
X01628Y04226*
X01628Y04226*
X01628Y04226*
X01628Y04225*
X01629Y04225*
X01629Y04225*
X01629Y04225*
X0163Y04225*
X0163Y04225*
X0163Y04225*
X01631Y04225*
X01631Y04225*
X01631*
X01632Y04225*
X01632Y04225*
X01632Y04225*
X01633Y04225*
X01633Y04225*
X01633Y04225*
X01634Y04225*
X01634Y04225*
X01634Y04226*
X01634Y04226*
X01635Y04226*
X01635Y04226*
X01635Y04227*
X01635Y04227*
X01635Y04227*
X01636Y04228*
X01636Y04228*
X01636Y04228*
X01636Y04229*
X01636Y04229*
X01636Y04229*
X01636Y0423*
X04332Y00833D02*
D01*
X04332Y00834*
X04332Y00834*
X04332Y00834*
X04332Y00835*
X04332Y00835*
X04332Y00835*
X04332Y00836*
X04331Y00836*
X04331Y00836*
X04331Y00837*
X04331Y00837*
X04331Y00837*
X0433Y00837*
X0433Y00837*
X0433Y00838*
X04329Y00838*
X04329Y00838*
X04329Y00838*
X04328Y00838*
X04328Y00838*
X04328Y00838*
X04327Y00838*
X04327*
X04327Y00838*
X04326Y00838*
X04326Y00838*
X04326Y00838*
X04325Y00838*
X04325Y00838*
X04325Y00838*
X04325Y00837*
X04324Y00837*
X04324Y00837*
X04324Y00837*
X04323Y00837*
X04323Y00836*
X04323Y00836*
X04323Y00836*
X04323Y00835*
X04323Y00835*
X04323Y00835*
X04322Y00834*
X04322Y00834*
X04322Y00834*
X04322Y00833*
X04322Y00833*
X04322Y00833*
X04322Y00832*
X04323Y00832*
X04323Y00832*
X04323Y00831*
X04323Y00831*
X04323Y00831*
X04323Y0083*
X04323Y0083*
X04324Y0083*
X04324Y0083*
X04324Y00829*
X04325Y00829*
X04325Y00829*
X04325Y00829*
X04325Y00829*
X04326Y00829*
X04326Y00829*
X04326Y00829*
X04327Y00828*
X04327Y00828*
X04327*
X04328Y00828*
X04328Y00829*
X04328Y00829*
X04329Y00829*
X04329Y00829*
X04329Y00829*
X0433Y00829*
X0433Y00829*
X0433Y00829*
X04331Y0083*
X04331Y0083*
X04331Y0083*
X04331Y0083*
X04331Y00831*
X04332Y00831*
X04332Y00831*
X04332Y00832*
X04332Y00832*
X04332Y00832*
X04332Y00833*
X04332Y00833*
X04332Y00833*
X01217Y00822D02*
D01*
X01217Y00822*
X01217Y00823*
X01216Y00823*
X01216Y00823*
X01216Y00824*
X01216Y00824*
X01216Y00824*
X01216Y00825*
X01216Y00825*
X01215Y00825*
X01215Y00825*
X01215Y00826*
X01215Y00826*
X01214Y00826*
X01214Y00826*
X01214Y00826*
X01214Y00826*
X01213Y00827*
X01213Y00827*
X01213Y00827*
X01212Y00827*
X01212Y00827*
X01211*
X01211Y00827*
X01211Y00827*
X0121Y00827*
X0121Y00827*
X0121Y00826*
X0121Y00826*
X01209Y00826*
X01209Y00826*
X01209Y00826*
X01208Y00826*
X01208Y00825*
X01208Y00825*
X01208Y00825*
X01207Y00825*
X01207Y00824*
X01207Y00824*
X01207Y00824*
X01207Y00823*
X01207Y00823*
X01207Y00823*
X01207Y00822*
X01207Y00822*
X01207Y00822*
X01207Y00821*
X01207Y00821*
X01207Y00821*
X01207Y0082*
X01207Y0082*
X01207Y0082*
X01207Y00819*
X01208Y00819*
X01208Y00819*
X01208Y00818*
X01208Y00818*
X01209Y00818*
X01209Y00818*
X01209Y00818*
X0121Y00817*
X0121Y00817*
X0121Y00817*
X0121Y00817*
X01211Y00817*
X01211Y00817*
X01211Y00817*
X01212*
X01212Y00817*
X01213Y00817*
X01213Y00817*
X01213Y00817*
X01214Y00817*
X01214Y00817*
X01214Y00818*
X01214Y00818*
X01215Y00818*
X01215Y00818*
X01215Y00818*
X01215Y00819*
X01216Y00819*
X01216Y00819*
X01216Y0082*
X01216Y0082*
X01216Y0082*
X01216Y00821*
X01216Y00821*
X01217Y00821*
X01217Y00822*
X01217Y00822*
X02896Y0375D02*
D01*
X02896Y0375*
X02896Y03751*
X02896Y03751*
X02896Y03751*
X02896Y03752*
X02896Y03752*
X02896Y03752*
X02896Y03752*
X02895Y03753*
X02895Y03753*
X02895Y03753*
X02895Y03754*
X02894Y03754*
X02894Y03754*
X02894Y03754*
X02894Y03754*
X02893Y03754*
X02893Y03755*
X02893Y03755*
X02892Y03755*
X02892Y03755*
X02892Y03755*
X02891*
X02891Y03755*
X02891Y03755*
X0289Y03755*
X0289Y03755*
X0289Y03754*
X02889Y03754*
X02889Y03754*
X02889Y03754*
X02888Y03754*
X02888Y03754*
X02888Y03753*
X02888Y03753*
X02887Y03753*
X02887Y03752*
X02887Y03752*
X02887Y03752*
X02887Y03752*
X02887Y03751*
X02887Y03751*
X02887Y03751*
X02887Y0375*
X02887Y0375*
X02887Y0375*
X02887Y03749*
X02887Y03749*
X02887Y03748*
X02887Y03748*
X02887Y03748*
X02887Y03748*
X02887Y03747*
X02887Y03747*
X02888Y03747*
X02888Y03746*
X02888Y03746*
X02888Y03746*
X02889Y03746*
X02889Y03746*
X02889Y03745*
X0289Y03745*
X0289Y03745*
X0289Y03745*
X02891Y03745*
X02891Y03745*
X02891Y03745*
X02892*
X02892Y03745*
X02892Y03745*
X02893Y03745*
X02893Y03745*
X02893Y03745*
X02894Y03745*
X02894Y03746*
X02894Y03746*
X02894Y03746*
X02895Y03746*
X02895Y03746*
X02895Y03747*
X02895Y03747*
X02896Y03747*
X02896Y03748*
X02896Y03748*
X02896Y03748*
X02896Y03748*
X02896Y03749*
X02896Y03749*
X02896Y0375*
X02896Y0375*
X02781D02*
D01*
X02781Y0375*
X02781Y03751*
X02781Y03751*
X02781Y03751*
X02781Y03752*
X02781Y03752*
X02781Y03752*
X02781Y03752*
X0278Y03753*
X0278Y03753*
X0278Y03753*
X0278Y03754*
X02779Y03754*
X02779Y03754*
X02779Y03754*
X02779Y03754*
X02778Y03754*
X02778Y03755*
X02778Y03755*
X02777Y03755*
X02777Y03755*
X02777Y03755*
X02776*
X02776Y03755*
X02776Y03755*
X02775Y03755*
X02775Y03755*
X02775Y03754*
X02774Y03754*
X02774Y03754*
X02774Y03754*
X02773Y03754*
X02773Y03754*
X02773Y03753*
X02773Y03753*
X02772Y03753*
X02772Y03752*
X02772Y03752*
X02772Y03752*
X02772Y03752*
X02772Y03751*
X02772Y03751*
X02772Y03751*
X02772Y0375*
X02772Y0375*
X02772Y0375*
X02772Y03749*
X02772Y03749*
X02772Y03748*
X02772Y03748*
X02772Y03748*
X02772Y03748*
X02772Y03747*
X02772Y03747*
X02773Y03747*
X02773Y03746*
X02773Y03746*
X02773Y03746*
X02774Y03746*
X02774Y03746*
X02774Y03745*
X02775Y03745*
X02775Y03745*
X02775Y03745*
X02776Y03745*
X02776Y03745*
X02776Y03745*
X02777*
X02777Y03745*
X02777Y03745*
X02778Y03745*
X02778Y03745*
X02778Y03745*
X02779Y03745*
X02779Y03746*
X02779Y03746*
X02779Y03746*
X0278Y03746*
X0278Y03746*
X0278Y03747*
X0278Y03747*
X02781Y03747*
X02781Y03748*
X02781Y03748*
X02781Y03748*
X02781Y03748*
X02781Y03749*
X02781Y03749*
X02781Y0375*
X02781Y0375*
X03306D02*
D01*
X03306Y0375*
X03306Y03751*
X03306Y03751*
X03306Y03751*
X03306Y03752*
X03306Y03752*
X03306Y03752*
X03306Y03752*
X03305Y03753*
X03305Y03753*
X03305Y03753*
X03305Y03754*
X03304Y03754*
X03304Y03754*
X03304Y03754*
X03304Y03754*
X03303Y03754*
X03303Y03755*
X03303Y03755*
X03302Y03755*
X03302Y03755*
X03302Y03755*
X03301*
X03301Y03755*
X03301Y03755*
X033Y03755*
X033Y03755*
X033Y03754*
X03299Y03754*
X03299Y03754*
X03299Y03754*
X03298Y03754*
X03298Y03754*
X03298Y03753*
X03298Y03753*
X03297Y03753*
X03297Y03752*
X03297Y03752*
X03297Y03752*
X03297Y03752*
X03297Y03751*
X03297Y03751*
X03297Y03751*
X03297Y0375*
X03297Y0375*
X03297Y0375*
X03297Y03749*
X03297Y03749*
X03297Y03748*
X03297Y03748*
X03297Y03748*
X03297Y03748*
X03297Y03747*
X03297Y03747*
X03298Y03747*
X03298Y03746*
X03298Y03746*
X03298Y03746*
X03299Y03746*
X03299Y03746*
X03299Y03745*
X033Y03745*
X033Y03745*
X033Y03745*
X03301Y03745*
X03301Y03745*
X03301Y03745*
X03302*
X03302Y03745*
X03302Y03745*
X03303Y03745*
X03303Y03745*
X03303Y03745*
X03304Y03745*
X03304Y03746*
X03304Y03746*
X03304Y03746*
X03305Y03746*
X03305Y03746*
X03305Y03747*
X03305Y03747*
X03306Y03747*
X03306Y03748*
X03306Y03748*
X03306Y03748*
X03306Y03748*
X03306Y03749*
X03306Y03749*
X03306Y0375*
X03306Y0375*
X01217Y01872D02*
D01*
X01217Y01872*
X01217Y01873*
X01216Y01873*
X01216Y01873*
X01216Y01874*
X01216Y01874*
X01216Y01874*
X01216Y01875*
X01216Y01875*
X01215Y01875*
X01215Y01875*
X01215Y01876*
X01215Y01876*
X01214Y01876*
X01214Y01876*
X01214Y01876*
X01214Y01876*
X01213Y01877*
X01213Y01877*
X01213Y01877*
X01212Y01877*
X01212Y01877*
X01211*
X01211Y01877*
X01211Y01877*
X0121Y01877*
X0121Y01877*
X0121Y01876*
X0121Y01876*
X01209Y01876*
X01209Y01876*
X01209Y01876*
X01208Y01876*
X01208Y01875*
X01208Y01875*
X01208Y01875*
X01207Y01875*
X01207Y01874*
X01207Y01874*
X01207Y01874*
X01207Y01873*
X01207Y01873*
X01207Y01873*
X01207Y01872*
X01207Y01872*
X01207Y01872*
X01207Y01871*
X01207Y01871*
X01207Y01871*
X01207Y0187*
X01207Y0187*
X01207Y0187*
X01207Y01869*
X01208Y01869*
X01208Y01869*
X01208Y01868*
X01208Y01868*
X01209Y01868*
X01209Y01868*
X01209Y01868*
X0121Y01867*
X0121Y01867*
X0121Y01867*
X0121Y01867*
X01211Y01867*
X01211Y01867*
X01211Y01867*
X01212*
X01212Y01867*
X01213Y01867*
X01213Y01867*
X01213Y01867*
X01214Y01867*
X01214Y01867*
X01214Y01868*
X01214Y01868*
X01215Y01868*
X01215Y01868*
X01215Y01868*
X01215Y01869*
X01216Y01869*
X01216Y01869*
X01216Y0187*
X01216Y0187*
X01216Y0187*
X01216Y01871*
X01216Y01871*
X01217Y01871*
X01217Y01872*
X01217Y01872*
Y02397D02*
D01*
X01217Y02397*
X01217Y02398*
X01216Y02398*
X01216Y02398*
X01216Y02399*
X01216Y02399*
X01216Y02399*
X01216Y024*
X01216Y024*
X01215Y024*
X01215Y024*
X01215Y02401*
X01215Y02401*
X01214Y02401*
X01214Y02401*
X01214Y02401*
X01214Y02401*
X01213Y02402*
X01213Y02402*
X01213Y02402*
X01212Y02402*
X01212Y02402*
X01211*
X01211Y02402*
X01211Y02402*
X0121Y02402*
X0121Y02402*
X0121Y02401*
X0121Y02401*
X01209Y02401*
X01209Y02401*
X01209Y02401*
X01208Y02401*
X01208Y024*
X01208Y024*
X01208Y024*
X01207Y024*
X01207Y02399*
X01207Y02399*
X01207Y02399*
X01207Y02398*
X01207Y02398*
X01207Y02398*
X01207Y02397*
X01207Y02397*
X01207Y02397*
X01207Y02396*
X01207Y02396*
X01207Y02396*
X01207Y02395*
X01207Y02395*
X01207Y02395*
X01207Y02394*
X01208Y02394*
X01208Y02394*
X01208Y02393*
X01208Y02393*
X01209Y02393*
X01209Y02393*
X01209Y02393*
X0121Y02392*
X0121Y02392*
X0121Y02392*
X0121Y02392*
X01211Y02392*
X01211Y02392*
X01211Y02392*
X01212*
X01212Y02392*
X01213Y02392*
X01213Y02392*
X01213Y02392*
X01214Y02392*
X01214Y02392*
X01214Y02393*
X01214Y02393*
X01215Y02393*
X01215Y02393*
X01215Y02393*
X01215Y02394*
X01216Y02394*
X01216Y02394*
X01216Y02395*
X01216Y02395*
X01216Y02395*
X01216Y02396*
X01216Y02396*
X01217Y02396*
X01217Y02397*
X01217Y02397*
Y01347D02*
D01*
X01217Y01347*
X01217Y01348*
X01216Y01348*
X01216Y01348*
X01216Y01349*
X01216Y01349*
X01216Y01349*
X01216Y0135*
X01216Y0135*
X01215Y0135*
X01215Y0135*
X01215Y01351*
X01215Y01351*
X01214Y01351*
X01214Y01351*
X01214Y01351*
X01214Y01351*
X01213Y01352*
X01213Y01352*
X01213Y01352*
X01212Y01352*
X01212Y01352*
X01211*
X01211Y01352*
X01211Y01352*
X0121Y01352*
X0121Y01352*
X0121Y01351*
X0121Y01351*
X01209Y01351*
X01209Y01351*
X01209Y01351*
X01208Y01351*
X01208Y0135*
X01208Y0135*
X01208Y0135*
X01207Y0135*
X01207Y01349*
X01207Y01349*
X01207Y01349*
X01207Y01348*
X01207Y01348*
X01207Y01348*
X01207Y01347*
X01207Y01347*
X01207Y01347*
X01207Y01346*
X01207Y01346*
X01207Y01346*
X01207Y01345*
X01207Y01345*
X01207Y01345*
X01207Y01344*
X01208Y01344*
X01208Y01344*
X01208Y01343*
X01208Y01343*
X01209Y01343*
X01209Y01343*
X01209Y01343*
X0121Y01342*
X0121Y01342*
X0121Y01342*
X0121Y01342*
X01211Y01342*
X01211Y01342*
X01211Y01342*
X01212*
X01212Y01342*
X01213Y01342*
X01213Y01342*
X01213Y01342*
X01214Y01342*
X01214Y01342*
X01214Y01343*
X01214Y01343*
X01215Y01343*
X01215Y01343*
X01215Y01343*
X01215Y01344*
X01216Y01344*
X01216Y01344*
X01216Y01345*
X01216Y01345*
X01216Y01345*
X01216Y01346*
X01216Y01346*
X01217Y01346*
X01217Y01347*
X01217Y01347*
X03777Y03889D02*
D01*
X03777Y03889*
X03777Y03889*
X03777Y0389*
X03777Y0389*
X03777Y0389*
X03777Y03891*
X03776Y03891*
X03776Y03891*
X03776Y03891*
X03776Y03892*
X03776Y03892*
X03775Y03892*
X03775Y03892*
X03775Y03893*
X03775Y03893*
X03774Y03893*
X03774Y03893*
X03774Y03893*
X03773Y03893*
X03773Y03893*
X03773Y03893*
X03772Y03893*
X03772*
X03772Y03893*
X03771Y03893*
X03771Y03893*
X03771Y03893*
X0377Y03893*
X0377Y03893*
X0377Y03893*
X03769Y03893*
X03769Y03892*
X03769Y03892*
X03769Y03892*
X03768Y03892*
X03768Y03891*
X03768Y03891*
X03768Y03891*
X03768Y03891*
X03767Y0389*
X03767Y0389*
X03767Y0389*
X03767Y03889*
X03767Y03889*
X03767Y03889*
X03767Y03888*
X03767Y03888*
X03767Y03888*
X03767Y03887*
X03767Y03887*
X03768Y03887*
X03768Y03886*
X03768Y03886*
X03768Y03886*
X03768Y03885*
X03769Y03885*
X03769Y03885*
X03769Y03885*
X03769Y03885*
X0377Y03884*
X0377Y03884*
X0377Y03884*
X03771Y03884*
X03771Y03884*
X03771Y03884*
X03772Y03884*
X03772Y03884*
X03772*
X03773Y03884*
X03773Y03884*
X03773Y03884*
X03774Y03884*
X03774Y03884*
X03774Y03884*
X03775Y03884*
X03775Y03885*
X03775Y03885*
X03775Y03885*
X03776Y03885*
X03776Y03885*
X03776Y03886*
X03776Y03886*
X03776Y03886*
X03777Y03887*
X03777Y03887*
X03777Y03887*
X03777Y03888*
X03777Y03888*
X03777Y03888*
X03777Y03889*
G54D11*
X03441Y02087D02*
D01*
X03441Y02087*
X03441Y02088*
X03441Y02089*
X0344Y02089*
X0344Y0209*
X0344Y0209*
X0344Y02091*
X0344Y02091*
X03439Y02092*
X03439Y02092*
X03439Y02092*
X03438Y02093*
X03438Y02093*
X03437Y02093*
X03437Y02094*
X03436Y02094*
X03436Y02094*
X03435Y02094*
X03435Y02095*
X03434Y02095*
X03434Y02095*
X03433Y02095*
X03433*
X03432Y02095*
X03431Y02095*
X03431Y02095*
X0343Y02094*
X0343Y02094*
X03429Y02094*
X03429Y02094*
X03428Y02093*
X03428Y02093*
X03428Y02093*
X03427Y02092*
X03427Y02092*
X03426Y02092*
X03426Y02091*
X03426Y02091*
X03426Y0209*
X03425Y0209*
X03425Y02089*
X03425Y02089*
X03425Y02088*
X03425Y02087*
X03425Y02087*
X03425Y02086*
X03425Y02086*
X03425Y02085*
X03425Y02085*
X03425Y02084*
X03426Y02084*
X03426Y02083*
X03426Y02083*
X03426Y02082*
X03427Y02082*
X03427Y02081*
X03428Y02081*
X03428Y02081*
X03428Y0208*
X03429Y0208*
X03429Y0208*
X0343Y0208*
X0343Y02079*
X03431Y02079*
X03431Y02079*
X03432Y02079*
X03433Y02079*
X03433*
X03434Y02079*
X03434Y02079*
X03435Y02079*
X03435Y02079*
X03436Y0208*
X03436Y0208*
X03437Y0208*
X03437Y0208*
X03438Y02081*
X03438Y02081*
X03439Y02081*
X03439Y02082*
X03439Y02082*
X0344Y02083*
X0344Y02083*
X0344Y02084*
X0344Y02084*
X0344Y02085*
X03441Y02085*
X03441Y02086*
X03441Y02086*
X03441Y02087*
X02219Y02299D02*
D01*
X02219Y023*
X02219Y023*
X02219Y02301*
X02219Y02301*
X02218Y02302*
X02218Y02302*
X02218Y02303*
X02218Y02303*
X02217Y02304*
X02217Y02304*
X02217Y02305*
X02216Y02305*
X02216Y02305*
X02215Y02306*
X02215Y02306*
X02215Y02306*
X02214Y02306*
X02214Y02307*
X02213Y02307*
X02212Y02307*
X02212Y02307*
X02211Y02307*
X02211*
X0221Y02307*
X0221Y02307*
X02209Y02307*
X02209Y02307*
X02208Y02306*
X02208Y02306*
X02207Y02306*
X02207Y02306*
X02206Y02305*
X02206Y02305*
X02205Y02305*
X02205Y02304*
X02205Y02304*
X02204Y02303*
X02204Y02303*
X02204Y02302*
X02204Y02302*
X02204Y02301*
X02203Y02301*
X02203Y023*
X02203Y023*
X02203Y02299*
X02203Y02299*
X02203Y02298*
X02203Y02297*
X02204Y02297*
X02204Y02296*
X02204Y02296*
X02204Y02295*
X02204Y02295*
X02205Y02294*
X02205Y02294*
X02205Y02294*
X02206Y02293*
X02206Y02293*
X02207Y02293*
X02207Y02292*
X02208Y02292*
X02208Y02292*
X02209Y02292*
X02209Y02291*
X0221Y02291*
X0221Y02291*
X02211Y02291*
X02211*
X02212Y02291*
X02212Y02291*
X02213Y02291*
X02214Y02292*
X02214Y02292*
X02215Y02292*
X02215Y02292*
X02215Y02293*
X02216Y02293*
X02216Y02293*
X02217Y02294*
X02217Y02294*
X02217Y02294*
X02218Y02295*
X02218Y02295*
X02218Y02296*
X02218Y02296*
X02219Y02297*
X02219Y02297*
X02219Y02298*
X02219Y02299*
X02219Y02299*
X01842Y01317D02*
D01*
X01842Y01318*
X01842Y01318*
X01842Y01319*
X01842Y01319*
X01841Y0132*
X01841Y0132*
X01841Y01321*
X01841Y01321*
X0184Y01322*
X0184Y01322*
X0184Y01323*
X01839Y01323*
X01839Y01323*
X01838Y01324*
X01838Y01324*
X01837Y01324*
X01837Y01325*
X01836Y01325*
X01836Y01325*
X01835Y01325*
X01835Y01325*
X01834Y01325*
X01834*
X01833Y01325*
X01833Y01325*
X01832Y01325*
X01832Y01325*
X01831Y01325*
X0183Y01324*
X0183Y01324*
X0183Y01324*
X01829Y01323*
X01829Y01323*
X01828Y01323*
X01828Y01322*
X01828Y01322*
X01827Y01321*
X01827Y01321*
X01827Y0132*
X01827Y0132*
X01826Y01319*
X01826Y01319*
X01826Y01318*
X01826Y01318*
X01826Y01317*
X01826Y01317*
X01826Y01316*
X01826Y01316*
X01826Y01315*
X01827Y01315*
X01827Y01314*
X01827Y01314*
X01827Y01313*
X01828Y01313*
X01828Y01312*
X01828Y01312*
X01829Y01311*
X01829Y01311*
X0183Y01311*
X0183Y0131*
X0183Y0131*
X01831Y0131*
X01832Y0131*
X01832Y0131*
X01833Y01309*
X01833Y01309*
X01834Y01309*
X01834*
X01835Y01309*
X01835Y01309*
X01836Y0131*
X01836Y0131*
X01837Y0131*
X01837Y0131*
X01838Y0131*
X01838Y01311*
X01839Y01311*
X01839Y01311*
X0184Y01312*
X0184Y01312*
X0184Y01313*
X01841Y01313*
X01841Y01314*
X01841Y01314*
X01841Y01315*
X01842Y01315*
X01842Y01316*
X01842Y01316*
X01842Y01317*
X01842Y01317*
X02989Y01095D02*
D01*
X02989Y01096*
X02989Y01096*
X02989Y01097*
X02988Y01097*
X02988Y01098*
X02988Y01098*
X02988Y01099*
X02988Y01099*
X02987Y011*
X02987Y011*
X02986Y01101*
X02986Y01101*
X02986Y01101*
X02985Y01102*
X02985Y01102*
X02984Y01102*
X02984Y01102*
X02983Y01103*
X02983Y01103*
X02982Y01103*
X02982Y01103*
X02981Y01103*
X02981*
X0298Y01103*
X02979Y01103*
X02979Y01103*
X02978Y01103*
X02978Y01102*
X02977Y01102*
X02977Y01102*
X02976Y01102*
X02976Y01101*
X02976Y01101*
X02975Y01101*
X02975Y011*
X02974Y011*
X02974Y01099*
X02974Y01099*
X02974Y01098*
X02973Y01098*
X02973Y01097*
X02973Y01097*
X02973Y01096*
X02973Y01096*
X02973Y01095*
X02973Y01095*
X02973Y01094*
X02973Y01094*
X02973Y01093*
X02973Y01092*
X02974Y01092*
X02974Y01091*
X02974Y01091*
X02974Y01091*
X02975Y0109*
X02975Y0109*
X02976Y01089*
X02976Y01089*
X02976Y01089*
X02977Y01088*
X02977Y01088*
X02978Y01088*
X02978Y01088*
X02979Y01088*
X02979Y01087*
X0298Y01087*
X02981Y01087*
X02981*
X02982Y01087*
X02982Y01087*
X02983Y01088*
X02983Y01088*
X02984Y01088*
X02984Y01088*
X02985Y01088*
X02985Y01089*
X02986Y01089*
X02986Y01089*
X02986Y0109*
X02987Y0109*
X02987Y01091*
X02988Y01091*
X02988Y01091*
X02988Y01092*
X02988Y01092*
X02988Y01093*
X02989Y01094*
X02989Y01094*
X02989Y01095*
X02989Y01095*
G54D12*
X02863Y03279D02*
D01*
X02863Y0328*
X02863Y03281*
X02862Y03281*
X02862Y03282*
X02862Y03283*
X02862Y03284*
X02861Y03285*
X02861Y03285*
X0286Y03286*
X0286Y03287*
X02859Y03287*
X02859Y03288*
X02858Y03288*
X02857Y03289*
X02857Y03289*
X02856Y0329*
X02855Y0329*
X02855Y0329*
X02854Y0329*
X02853Y03291*
X02852Y03291*
X02851Y03291*
X0285*
X0285Y03291*
X02849Y03291*
X02848Y0329*
X02847Y0329*
X02846Y0329*
X02846Y0329*
X02845Y03289*
X02844Y03289*
X02844Y03288*
X02843Y03288*
X02842Y03287*
X02842Y03287*
X02841Y03286*
X02841Y03285*
X0284Y03285*
X0284Y03284*
X0284Y03283*
X0284Y03282*
X02839Y03281*
X02839Y03281*
X02839Y0328*
X02839Y03279*
X02839Y03278*
X02839Y03277*
X02839Y03277*
X0284Y03276*
X0284Y03275*
X0284Y03274*
X0284Y03273*
X02841Y03273*
X02841Y03272*
X02842Y03271*
X02842Y03271*
X02843Y0327*
X02844Y0327*
X02844Y03269*
X02845Y03269*
X02846Y03268*
X02846Y03268*
X02847Y03268*
X02848Y03268*
X02849Y03267*
X0285Y03267*
X0285Y03267*
X02851*
X02852Y03267*
X02853Y03267*
X02854Y03268*
X02855Y03268*
X02855Y03268*
X02856Y03268*
X02857Y03269*
X02857Y03269*
X02858Y0327*
X02859Y0327*
X02859Y03271*
X0286Y03271*
X0286Y03272*
X02861Y03273*
X02861Y03273*
X02862Y03274*
X02862Y03275*
X02862Y03276*
X02862Y03277*
X02863Y03277*
X02863Y03278*
X02863Y03279*
X01727Y04171D02*
D01*
X01727Y04171*
X01726Y04172*
X01726Y04173*
X01726Y04174*
X01726Y04175*
X01726Y04175*
X01725Y04176*
X01725Y04177*
X01724Y04178*
X01724Y04178*
X01723Y04179*
X01723Y04179*
X01722Y0418*
X01721Y0418*
X01721Y04181*
X0172Y04181*
X01719Y04182*
X01718Y04182*
X01718Y04182*
X01717Y04182*
X01716Y04182*
X01715Y04182*
X01714*
X01713Y04182*
X01713Y04182*
X01712Y04182*
X01711Y04182*
X0171Y04182*
X0171Y04181*
X01709Y04181*
X01708Y0418*
X01707Y0418*
X01707Y04179*
X01706Y04179*
X01706Y04178*
X01705Y04178*
X01705Y04177*
X01704Y04176*
X01704Y04175*
X01704Y04175*
X01703Y04174*
X01703Y04173*
X01703Y04172*
X01703Y04171*
X01703Y04171*
X01703Y0417*
X01703Y04169*
X01703Y04168*
X01703Y04167*
X01704Y04167*
X01704Y04166*
X01704Y04165*
X01705Y04164*
X01705Y04164*
X01706Y04163*
X01706Y04162*
X01707Y04162*
X01707Y04161*
X01708Y04161*
X01709Y0416*
X0171Y0416*
X0171Y0416*
X01711Y04159*
X01712Y04159*
X01713Y04159*
X01713Y04159*
X01714Y04159*
X01715*
X01716Y04159*
X01717Y04159*
X01718Y04159*
X01718Y04159*
X01719Y0416*
X0172Y0416*
X01721Y0416*
X01721Y04161*
X01722Y04161*
X01723Y04162*
X01723Y04162*
X01724Y04163*
X01724Y04164*
X01725Y04164*
X01725Y04165*
X01726Y04166*
X01726Y04167*
X01726Y04167*
X01726Y04168*
X01726Y04169*
X01727Y0417*
X01727Y04171*
X03868Y0383D02*
D01*
X03868Y0383*
X03867Y03831*
X03867Y03832*
X03867Y03833*
X03867Y03834*
X03867Y03834*
X03866Y03835*
X03866Y03836*
X03865Y03837*
X03865Y03837*
X03864Y03838*
X03864Y03838*
X03863Y03839*
X03862Y03839*
X03862Y0384*
X03861Y0384*
X0386Y03841*
X03859Y03841*
X03859Y03841*
X03858Y03841*
X03857Y03841*
X03856Y03841*
X03855*
X03854Y03841*
X03854Y03841*
X03853Y03841*
X03852Y03841*
X03851Y03841*
X03851Y0384*
X0385Y0384*
X03849Y03839*
X03848Y03839*
X03848Y03838*
X03847Y03838*
X03847Y03837*
X03846Y03837*
X03846Y03836*
X03845Y03835*
X03845Y03834*
X03845Y03834*
X03844Y03833*
X03844Y03832*
X03844Y03831*
X03844Y0383*
X03844Y0383*
X03844Y03829*
X03844Y03828*
X03844Y03827*
X03844Y03826*
X03845Y03826*
X03845Y03825*
X03845Y03824*
X03846Y03823*
X03846Y03823*
X03847Y03822*
X03847Y03821*
X03848Y03821*
X03848Y0382*
X03849Y0382*
X0385Y03819*
X03851Y03819*
X03851Y03819*
X03852Y03818*
X03853Y03818*
X03854Y03818*
X03854Y03818*
X03855Y03818*
X03856*
X03857Y03818*
X03858Y03818*
X03859Y03818*
X03859Y03818*
X0386Y03819*
X03861Y03819*
X03862Y03819*
X03862Y0382*
X03863Y0382*
X03864Y03821*
X03864Y03821*
X03865Y03822*
X03865Y03823*
X03866Y03823*
X03866Y03824*
X03867Y03825*
X03867Y03826*
X03867Y03826*
X03867Y03827*
X03867Y03828*
X03868Y03829*
X03868Y0383*
G54D13*
X06191Y03733D02*
D01*
X06191Y03733*
X06191Y03733*
X06191Y03733*
X06191Y03734*
X0619Y03734*
X0619Y03734*
X0619Y03734*
X0619Y03734*
X0619Y03734*
X0619Y03734*
X0619Y03734*
X0619Y03735*
X0619Y03735*
X0619Y03735*
X0619Y03735*
X06189Y03735*
X06189Y03735*
X06189Y03735*
X06189Y03735*
X06189Y03735*
X06189Y03735*
X06189Y03735*
X06189*
X06188Y03735*
X06188Y03735*
X06188Y03735*
X06188Y03735*
X06188Y03735*
X06188Y03735*
X06188Y03735*
X06188Y03735*
X06187Y03735*
X06187Y03735*
X06187Y03734*
X06187Y03734*
X06187Y03734*
X06187Y03734*
X06187Y03734*
X06187Y03734*
X06187Y03734*
X06187Y03734*
X06187Y03733*
X06187Y03733*
X06187Y03733*
X06187Y03733*
X06187Y03733*
X06187Y03733*
X06187Y03733*
X06187Y03732*
X06187Y03732*
X06187Y03732*
X06187Y03732*
X06187Y03732*
X06187Y03732*
X06187Y03732*
X06187Y03732*
X06187Y03732*
X06187Y03731*
X06188Y03731*
X06188Y03731*
X06188Y03731*
X06188Y03731*
X06188Y03731*
X06188Y03731*
X06188Y03731*
X06188Y03731*
X06189Y03731*
X06189*
X06189Y03731*
X06189Y03731*
X06189Y03731*
X06189Y03731*
X06189Y03731*
X06189Y03731*
X0619Y03731*
X0619Y03731*
X0619Y03731*
X0619Y03732*
X0619Y03732*
X0619Y03732*
X0619Y03732*
X0619Y03732*
X0619Y03732*
X0619Y03732*
X0619Y03732*
X06191Y03732*
X06191Y03733*
X06191Y03733*
X06191Y03733*
X06191Y03733*
X01223Y04175D02*
D01*
X01223Y04176*
X01223Y04176*
X01223Y04176*
X01223Y04176*
X01223Y04176*
X01223Y04176*
X01223Y04176*
X01222Y04176*
X01222Y04177*
X01222Y04177*
X01222Y04177*
X01222Y04177*
X01222Y04177*
X01222Y04177*
X01222Y04177*
X01222Y04177*
X01222Y04177*
X01221Y04177*
X01221Y04177*
X01221Y04177*
X01221Y04177*
X01221Y04177*
X01221*
X01221Y04177*
X0122Y04177*
X0122Y04177*
X0122Y04177*
X0122Y04177*
X0122Y04177*
X0122Y04177*
X0122Y04177*
X0122Y04177*
X01219Y04177*
X01219Y04177*
X01219Y04177*
X01219Y04177*
X01219Y04176*
X01219Y04176*
X01219Y04176*
X01219Y04176*
X01219Y04176*
X01219Y04176*
X01219Y04176*
X01219Y04176*
X01219Y04175*
X01219Y04175*
X01219Y04175*
X01219Y04175*
X01219Y04175*
X01219Y04175*
X01219Y04175*
X01219Y04174*
X01219Y04174*
X01219Y04174*
X01219Y04174*
X01219Y04174*
X01219Y04174*
X0122Y04174*
X0122Y04174*
X0122Y04174*
X0122Y04174*
X0122Y04174*
X0122Y04173*
X0122Y04173*
X0122Y04173*
X01221Y04173*
X01221Y04173*
X01221*
X01221Y04173*
X01221Y04173*
X01221Y04173*
X01221Y04173*
X01222Y04174*
X01222Y04174*
X01222Y04174*
X01222Y04174*
X01222Y04174*
X01222Y04174*
X01222Y04174*
X01222Y04174*
X01222Y04174*
X01222Y04174*
X01223Y04174*
X01223Y04175*
X01223Y04175*
X01223Y04175*
X01223Y04175*
X01223Y04175*
X01223Y04175*
X01223Y04175*
X0325Y02866D02*
D01*
X0325Y02866*
X0325Y02866*
X0325Y02866*
X0325Y02866*
X0325Y02866*
X0325Y02866*
X0325Y02867*
X0325Y02867*
X0325Y02867*
X0325Y02867*
X0325Y02867*
X0325Y02867*
X0325Y02867*
X0325Y02867*
X03249Y02867*
X03249Y02867*
X03249Y02867*
X03249Y02868*
X03249Y02868*
X03249Y02868*
X03249Y02868*
X03249Y02868*
X03248*
X03248Y02868*
X03248Y02868*
X03248Y02868*
X03248Y02868*
X03248Y02867*
X03248Y02867*
X03248Y02867*
X03247Y02867*
X03247Y02867*
X03247Y02867*
X03247Y02867*
X03247Y02867*
X03247Y02867*
X03247Y02867*
X03247Y02867*
X03247Y02866*
X03247Y02866*
X03247Y02866*
X03247Y02866*
X03247Y02866*
X03247Y02866*
X03247Y02866*
D01*
X03247Y02866*
X03247Y02865*
X03247Y02865*
X03247Y02865*
X03247Y02865*
X03247Y02865*
X03247Y02865*
X03247Y02865*
X03247Y02864*
X03247Y02864*
X03247Y02864*
X03247Y02864*
X03247Y02864*
X03247Y02864*
X03248Y02864*
X03248Y02864*
X03248Y02864*
X03248Y02864*
X03248Y02864*
X03248Y02864*
X03248Y02864*
X03248Y02864*
X03249*
X03249Y02864*
X03249Y02864*
X03249Y02864*
X03249Y02864*
X03249Y02864*
X03249Y02864*
X0325Y02864*
X0325Y02864*
X0325Y02864*
X0325Y02864*
X0325Y02864*
X0325Y02864*
X0325Y02864*
X0325Y02865*
X0325Y02865*
X0325Y02865*
X0325Y02865*
X0325Y02865*
X0325Y02865*
X0325Y02865*
X0325Y02866*
X0325Y02866*
X05881Y03733D02*
D01*
X05881Y03733*
X05881Y03733*
X05881Y03733*
X05881Y03734*
X0588Y03734*
X0588Y03734*
X0588Y03734*
X0588Y03734*
X0588Y03734*
X0588Y03734*
X0588Y03734*
X0588Y03735*
X0588Y03735*
X0588Y03735*
X0588Y03735*
X05879Y03735*
X05879Y03735*
X05879Y03735*
X05879Y03735*
X05879Y03735*
X05879Y03735*
X05879Y03735*
X05879*
X05878Y03735*
X05878Y03735*
X05878Y03735*
X05878Y03735*
X05878Y03735*
X05878Y03735*
X05878Y03735*
X05878Y03735*
X05877Y03735*
X05877Y03735*
X05877Y03734*
X05877Y03734*
X05877Y03734*
X05877Y03734*
X05877Y03734*
X05877Y03734*
X05877Y03734*
X05877Y03734*
X05877Y03733*
X05877Y03733*
X05877Y03733*
X05877Y03733*
X05877Y03733*
X05877Y03733*
X05877Y03733*
X05877Y03732*
X05877Y03732*
X05877Y03732*
X05877Y03732*
X05877Y03732*
X05877Y03732*
X05877Y03732*
X05877Y03732*
X05877Y03732*
X05877Y03731*
X05878Y03731*
X05878Y03731*
X05878Y03731*
X05878Y03731*
X05878Y03731*
X05878Y03731*
X05878Y03731*
X05878Y03731*
X05879Y03731*
X05879*
X05879Y03731*
X05879Y03731*
X05879Y03731*
X05879Y03731*
X05879Y03731*
X05879Y03731*
X0588Y03731*
X0588Y03731*
X0588Y03731*
X0588Y03732*
X0588Y03732*
X0588Y03732*
X0588Y03732*
X0588Y03732*
X0588Y03732*
X0588Y03732*
X0588Y03732*
X05881Y03732*
X05881Y03733*
X05881Y03733*
X05881Y03733*
X05881Y03733*
X06196Y03598D02*
D01*
X06196Y03598*
X06196Y03598*
X06196Y03598*
X06196Y03599*
X06195Y03599*
X06195Y03599*
X06195Y03599*
X06195Y03599*
X06195Y03599*
X06195Y03599*
X06195Y03599*
X06195Y036*
X06195Y036*
X06195Y036*
X06195Y036*
X06194Y036*
X06194Y036*
X06194Y036*
X06194Y036*
X06194Y036*
X06194Y036*
X06194Y036*
X06194*
X06193Y036*
X06193Y036*
X06193Y036*
X06193Y036*
X06193Y036*
X06193Y036*
X06193Y036*
X06193Y036*
X06192Y036*
X06192Y036*
X06192Y03599*
X06192Y03599*
X06192Y03599*
X06192Y03599*
X06192Y03599*
X06192Y03599*
X06192Y03599*
X06192Y03599*
X06192Y03598*
X06192Y03598*
X06192Y03598*
X06192Y03598*
X06192Y03598*
X06192Y03598*
X06192Y03598*
X06192Y03597*
X06192Y03597*
X06192Y03597*
X06192Y03597*
X06192Y03597*
X06192Y03597*
X06192Y03597*
X06192Y03597*
X06192Y03597*
X06192Y03596*
X06193Y03596*
X06193Y03596*
X06193Y03596*
X06193Y03596*
X06193Y03596*
X06193Y03596*
X06193Y03596*
X06193Y03596*
X06194Y03596*
X06194*
X06194Y03596*
X06194Y03596*
X06194Y03596*
X06194Y03596*
X06194Y03596*
X06194Y03596*
X06195Y03596*
X06195Y03596*
X06195Y03596*
X06195Y03597*
X06195Y03597*
X06195Y03597*
X06195Y03597*
X06195Y03597*
X06195Y03597*
X06195Y03597*
X06195Y03597*
X06196Y03597*
X06196Y03598*
X06196Y03598*
X06196Y03598*
X06196Y03598*
X04255Y03631D02*
D01*
X04255Y03632*
X04255Y03632*
X04255Y03632*
X04255Y03632*
X04255Y03632*
X04255Y03632*
X04255Y03632*
X04255Y03632*
X04255Y03633*
X04255Y03633*
X04255Y03633*
X04255Y03633*
X04255Y03633*
X04255Y03633*
X04254Y03633*
X04254Y03633*
X04254Y03633*
X04254Y03633*
X04254Y03633*
X04254Y03633*
X04254Y03633*
X04254Y03633*
X04253*
X04253Y03633*
X04253Y03633*
X04253Y03633*
X04253Y03633*
X04253Y03633*
X04253Y03633*
X04252Y03633*
X04252Y03633*
X04252Y03633*
X04252Y03633*
X04252Y03633*
X04252Y03633*
X04252Y03633*
X04252Y03632*
X04252Y03632*
X04252Y03632*
X04252Y03632*
X04252Y03632*
X04252Y03632*
X04251Y03632*
X04251Y03632*
X04251Y03631*
X04251Y03631*
X04251Y03631*
X04252Y03631*
X04252Y03631*
X04252Y03631*
X04252Y03631*
X04252Y0363*
X04252Y0363*
X04252Y0363*
X04252Y0363*
X04252Y0363*
X04252Y0363*
X04252Y0363*
X04252Y0363*
X04252Y0363*
X04253Y0363*
X04253Y0363*
X04253Y0363*
X04253Y03629*
X04253Y03629*
X04253Y03629*
X04253Y03629*
X04254*
X04254Y03629*
X04254Y03629*
X04254Y03629*
X04254Y0363*
X04254Y0363*
X04254Y0363*
X04254Y0363*
X04255Y0363*
X04255Y0363*
X04255Y0363*
X04255Y0363*
X04255Y0363*
X04255Y0363*
X04255Y0363*
X04255Y0363*
X04255Y03631*
X04255Y03631*
X04255Y03631*
X04255Y03631*
X04255Y03631*
X04255Y03631*
X04255Y03631*
X0362Y03931D02*
D01*
X0362Y03931*
X0362Y03931*
X0362Y03931*
X0362Y03931*
X0362Y03931*
X0362Y03932*
X0362Y03932*
X0362Y03932*
X03619Y03932*
X03619Y03932*
X03619Y03932*
X03619Y03932*
X03619Y03932*
X03619Y03932*
X03619Y03932*
X03619Y03933*
X03619Y03933*
X03618Y03933*
X03618Y03933*
X03618Y03933*
X03618Y03933*
X03618Y03933*
X03618*
X03618Y03933*
X03618Y03933*
X03617Y03933*
X03617Y03933*
X03617Y03933*
X03617Y03933*
X03617Y03932*
X03617Y03932*
X03617Y03932*
X03617Y03932*
X03616Y03932*
X03616Y03932*
X03616Y03932*
X03616Y03932*
X03616Y03932*
X03616Y03932*
X03616Y03931*
X03616Y03931*
X03616Y03931*
X03616Y03931*
X03616Y03931*
X03616Y03931*
X03616Y03931*
X03616Y0393*
X03616Y0393*
X03616Y0393*
X03616Y0393*
X03616Y0393*
X03616Y0393*
X03616Y0393*
X03616Y0393*
X03616Y03929*
X03616Y03929*
X03617Y03929*
X03617Y03929*
X03617Y03929*
X03617Y03929*
X03617Y03929*
X03617Y03929*
X03617Y03929*
X03617Y03929*
X03618Y03929*
X03618Y03929*
X03618Y03929*
X03618*
X03618Y03929*
X03618Y03929*
X03618Y03929*
X03618Y03929*
X03619Y03929*
X03619Y03929*
X03619Y03929*
X03619Y03929*
X03619Y03929*
X03619Y03929*
X03619Y03929*
X03619Y03929*
X03619Y0393*
X0362Y0393*
X0362Y0393*
X0362Y0393*
X0362Y0393*
X0362Y0393*
X0362Y0393*
X0362Y0393*
X0362Y03931*
X0362Y03931*
X03563Y03705D02*
D01*
X03563Y03706*
X03563Y03706*
X03563Y03706*
X03563Y03706*
X03563Y03706*
X03563Y03706*
X03563Y03706*
X03562Y03706*
X03562Y03707*
X03562Y03707*
X03562Y03707*
X03562Y03707*
X03562Y03707*
X03562Y03707*
X03562Y03707*
X03562Y03707*
X03562Y03707*
X03561Y03707*
X03561Y03707*
X03561Y03707*
X03561Y03707*
X03561Y03707*
X03561*
X03561Y03707*
X0356Y03707*
X0356Y03707*
X0356Y03707*
X0356Y03707*
X0356Y03707*
X0356Y03707*
X0356Y03707*
X0356Y03707*
X03559Y03707*
X03559Y03707*
X03559Y03707*
X03559Y03707*
X03559Y03706*
X03559Y03706*
X03559Y03706*
X03559Y03706*
X03559Y03706*
X03559Y03706*
X03559Y03706*
X03559Y03706*
X03559Y03705*
X03559Y03705*
X03559Y03705*
X03559Y03705*
X03559Y03705*
X03559Y03705*
X03559Y03705*
X03559Y03704*
X03559Y03704*
X03559Y03704*
X03559Y03704*
X03559Y03704*
X03559Y03704*
X0356Y03704*
X0356Y03704*
X0356Y03704*
X0356Y03704*
X0356Y03704*
X0356Y03703*
X0356Y03703*
X0356Y03703*
X03561Y03703*
X03561Y03703*
X03561*
X03561Y03703*
X03561Y03703*
X03561Y03703*
X03561Y03703*
X03562Y03704*
X03562Y03704*
X03562Y03704*
X03562Y03704*
X03562Y03704*
X03562Y03704*
X03562Y03704*
X03562Y03704*
X03562Y03704*
X03562Y03704*
X03563Y03704*
X03563Y03705*
X03563Y03705*
X03563Y03705*
X03563Y03705*
X03563Y03705*
X03563Y03705*
X03563Y03705*
X00618Y04175D02*
D01*
X00618Y04176*
X00618Y04176*
X00618Y04176*
X00618Y04176*
X00618Y04176*
X00618Y04176*
X00618Y04176*
X00617Y04176*
X00617Y04177*
X00617Y04177*
X00617Y04177*
X00617Y04177*
X00617Y04177*
X00617Y04177*
X00617Y04177*
X00617Y04177*
X00617Y04177*
X00616Y04177*
X00616Y04177*
X00616Y04177*
X00616Y04177*
X00616Y04177*
X00616*
X00616Y04177*
X00615Y04177*
X00615Y04177*
X00615Y04177*
X00615Y04177*
X00615Y04177*
X00615Y04177*
X00615Y04177*
X00615Y04177*
X00614Y04177*
X00614Y04177*
X00614Y04177*
X00614Y04177*
X00614Y04176*
X00614Y04176*
X00614Y04176*
X00614Y04176*
X00614Y04176*
X00614Y04176*
X00614Y04176*
X00614Y04176*
X00614Y04175*
X00614Y04175*
X00614Y04175*
X00614Y04175*
X00614Y04175*
X00614Y04175*
X00614Y04175*
X00614Y04174*
X00614Y04174*
X00614Y04174*
X00614Y04174*
X00614Y04174*
X00614Y04174*
X00615Y04174*
X00615Y04174*
X00615Y04174*
X00615Y04174*
X00615Y04174*
X00615Y04173*
X00615Y04173*
X00615Y04173*
X00616Y04173*
X00616Y04173*
X00616*
X00616Y04173*
X00616Y04173*
X00616Y04173*
X00616Y04173*
X00617Y04174*
X00617Y04174*
X00617Y04174*
X00617Y04174*
X00617Y04174*
X00617Y04174*
X00617Y04174*
X00617Y04174*
X00617Y04174*
X00617Y04174*
X00618Y04174*
X00618Y04175*
X00618Y04175*
X00618Y04175*
X00618Y04175*
X00618Y04175*
X00618Y04175*
X00618Y04175*
X00819D02*
D01*
X00819Y04176*
X00819Y04176*
X00819Y04176*
X00819Y04176*
X00819Y04176*
X00819Y04176*
X00819Y04176*
X00819Y04176*
X00819Y04177*
X00819Y04177*
X00819Y04177*
X00819Y04177*
X00819Y04177*
X00819Y04177*
X00818Y04177*
X00818Y04177*
X00818Y04177*
X00818Y04177*
X00818Y04177*
X00818Y04177*
X00818Y04177*
X00818Y04177*
X00817*
X00817Y04177*
X00817Y04177*
X00817Y04177*
X00817Y04177*
X00817Y04177*
X00817Y04177*
X00816Y04177*
X00816Y04177*
X00816Y04177*
X00816Y04177*
X00816Y04177*
X00816Y04177*
X00816Y04177*
X00816Y04176*
X00816Y04176*
X00816Y04176*
X00816Y04176*
X00816Y04176*
X00816Y04176*
X00816Y04176*
X00815Y04176*
X00815Y04175*
X00815Y04175*
X00816Y04175*
X00816Y04175*
X00816Y04175*
X00816Y04175*
X00816Y04175*
X00816Y04174*
X00816Y04174*
X00816Y04174*
X00816Y04174*
X00816Y04174*
X00816Y04174*
X00816Y04174*
X00816Y04174*
X00816Y04174*
X00817Y04174*
X00817Y04174*
X00817Y04173*
X00817Y04173*
X00817Y04173*
X00817Y04173*
X00817Y04173*
X00818*
X00818Y04173*
X00818Y04173*
X00818Y04173*
X00818Y04173*
X00818Y04174*
X00818Y04174*
X00818Y04174*
X00819Y04174*
X00819Y04174*
X00819Y04174*
X00819Y04174*
X00819Y04174*
X00819Y04174*
X00819Y04174*
X00819Y04174*
X00819Y04175*
X00819Y04175*
X00819Y04175*
X00819Y04175*
X00819Y04175*
X00819Y04175*
X00819Y04175*
X01021D02*
D01*
X01021Y04176*
X01021Y04176*
X01021Y04176*
X01021Y04176*
X01021Y04176*
X01021Y04176*
X01021Y04176*
X01021Y04176*
X01021Y04177*
X01021Y04177*
X01021Y04177*
X0102Y04177*
X0102Y04177*
X0102Y04177*
X0102Y04177*
X0102Y04177*
X0102Y04177*
X0102Y04177*
X0102Y04177*
X01019Y04177*
X01019Y04177*
X01019Y04177*
X01019*
X01019Y04177*
X01019Y04177*
X01019Y04177*
X01019Y04177*
X01018Y04177*
X01018Y04177*
X01018Y04177*
X01018Y04177*
X01018Y04177*
X01018Y04177*
X01018Y04177*
X01018Y04177*
X01018Y04177*
X01017Y04176*
X01017Y04176*
X01017Y04176*
X01017Y04176*
X01017Y04176*
X01017Y04176*
X01017Y04176*
X01017Y04176*
X01017Y04175*
X01017Y04175*
X01017Y04175*
X01017Y04175*
X01017Y04175*
X01017Y04175*
X01017Y04175*
X01017Y04174*
X01017Y04174*
X01018Y04174*
X01018Y04174*
X01018Y04174*
X01018Y04174*
X01018Y04174*
X01018Y04174*
X01018Y04174*
X01018Y04174*
X01018Y04174*
X01019Y04173*
X01019Y04173*
X01019Y04173*
X01019Y04173*
X01019Y04173*
X01019*
X01019Y04173*
X01019Y04173*
X0102Y04173*
X0102Y04173*
X0102Y04174*
X0102Y04174*
X0102Y04174*
X0102Y04174*
X0102Y04174*
X0102Y04174*
X01021Y04174*
X01021Y04174*
X01021Y04174*
X01021Y04174*
X01021Y04174*
X01021Y04175*
X01021Y04175*
X01021Y04175*
X01021Y04175*
X01021Y04175*
X01021Y04175*
X01021Y04175*
X03199Y02854D02*
X03219D01*
X03199Y02846D02*
Y02854D01*
Y02775D02*
Y02783D01*
Y02775D02*
X03219D01*
X03258D02*
X03278D01*
Y02783*
X03258Y02854D02*
X03278D01*
Y02846D02*
Y02854D01*
G54D14*
X06679Y03131D02*
D01*
X06679Y03131*
X06679Y03131*
X06679Y03132*
X06679Y03132*
X06679Y03132*
X06679Y03133*
X06679Y03133*
X06679Y03133*
X06678Y03133*
X06678Y03134*
X06678Y03134*
X06678Y03134*
X06677Y03135*
X06677Y03135*
X06677Y03135*
X06677Y03135*
X06676Y03135*
X06676Y03135*
X06676Y03135*
X06675Y03135*
X06675Y03136*
X06675Y03136*
X06674*
X06674Y03136*
X06673Y03135*
X06673Y03135*
X06673Y03135*
X06672Y03135*
X06672Y03135*
X06672Y03135*
X06672Y03135*
X06671Y03135*
X06671Y03134*
X06671Y03134*
X06671Y03134*
X0667Y03133*
X0667Y03133*
X0667Y03133*
X0667Y03133*
X0667Y03132*
X0667Y03132*
X06669Y03132*
X06669Y03131*
X06669Y03131*
X06669Y03131*
X06669Y0313*
X06669Y0313*
X06669Y0313*
X0667Y03129*
X0667Y03129*
X0667Y03129*
X0667Y03128*
X0667Y03128*
X0667Y03128*
X06671Y03127*
X06671Y03127*
X06671Y03127*
X06671Y03127*
X06672Y03126*
X06672Y03126*
X06672Y03126*
X06672Y03126*
X06673Y03126*
X06673Y03126*
X06673Y03126*
X06674Y03126*
X06674Y03126*
X06675*
X06675Y03126*
X06675Y03126*
X06676Y03126*
X06676Y03126*
X06676Y03126*
X06677Y03126*
X06677Y03126*
X06677Y03126*
X06677Y03127*
X06678Y03127*
X06678Y03127*
X06678Y03127*
X06678Y03128*
X06679Y03128*
X06679Y03128*
X06679Y03129*
X06679Y03129*
X06679Y03129*
X06679Y0313*
X06679Y0313*
X06679Y0313*
X06679Y03131*
X04129Y01599D02*
D01*
X04129Y01599*
X04129Y016*
X04129Y016*
X04129Y016*
X04129Y01601*
X04129Y01601*
X04129Y01601*
X04129Y01602*
X04128Y01602*
X04128Y01602*
X04128Y01603*
X04128Y01603*
X04127Y01603*
X04127Y01603*
X04127Y01603*
X04127Y01604*
X04126Y01604*
X04126Y01604*
X04126Y01604*
X04125Y01604*
X04125Y01604*
X04124Y01604*
X04124*
X04124Y01604*
X04123Y01604*
X04123Y01604*
X04123Y01604*
X04122Y01604*
X04122Y01604*
X04122Y01603*
X04122Y01603*
X04121Y01603*
X04121Y01603*
X04121Y01603*
X0412Y01602*
X0412Y01602*
X0412Y01602*
X0412Y01601*
X0412Y01601*
X0412Y01601*
X0412Y016*
X04119Y016*
X04119Y016*
X04119Y01599*
X04119Y01599*
X04119Y01599*
X04119Y01598*
X04119Y01598*
X0412Y01598*
X0412Y01597*
X0412Y01597*
X0412Y01597*
X0412Y01596*
X0412Y01596*
X0412Y01596*
X04121Y01596*
X04121Y01595*
X04121Y01595*
X04122Y01595*
X04122Y01595*
X04122Y01595*
X04122Y01594*
X04123Y01594*
X04123Y01594*
X04123Y01594*
X04124Y01594*
X04124Y01594*
X04124*
X04125Y01594*
X04125Y01594*
X04126Y01594*
X04126Y01594*
X04126Y01594*
X04127Y01595*
X04127Y01595*
X04127Y01595*
X04127Y01595*
X04128Y01595*
X04128Y01596*
X04128Y01596*
X04128Y01596*
X04129Y01596*
X04129Y01597*
X04129Y01597*
X04129Y01597*
X04129Y01598*
X04129Y01598*
X04129Y01598*
X04129Y01599*
X04129Y01599*
X02592Y02829D02*
D01*
X02592Y02834*
X02591Y02838*
X02591Y02842*
X0259Y02846*
X02588Y0285*
X02587Y02854*
X02585Y02858*
X02583Y02862*
X0258Y02865*
X02578Y02869*
X02575Y02872*
X02572Y02875*
X02568Y02878*
X02565Y0288*
X02561Y02882*
X02558Y02884*
X02554Y02886*
X0255Y02887*
X02546Y02889*
X02541Y0289*
X02537Y0289*
X02533Y0289*
X02529*
X02525Y0289*
X0252Y0289*
X02516Y02889*
X02512Y02887*
X02508Y02886*
X02504Y02884*
X025Y02882*
X02497Y0288*
X02493Y02878*
X0249Y02875*
X02487Y02872*
X02484Y02869*
X02482Y02865*
X02479Y02862*
X02477Y02858*
X02475Y02854*
X02474Y0285*
X02472Y02846*
X02471Y02842*
X0247Y02838*
X0247Y02834*
X0247Y02829*
X0247Y02825*
X0247Y02821*
X02471Y02817*
X02472Y02813*
X02474Y02809*
X02475Y02805*
X02477Y02801*
X02479Y02797*
X02482Y02794*
X02484Y0279*
X02487Y02787*
X0249Y02784*
X02493Y02781*
X02497Y02779*
X025Y02777*
X02504Y02775*
X02508Y02773*
X02512Y02771*
X02516Y0277*
X0252Y02769*
X02525Y02769*
X02529Y02768*
X02533*
X02537Y02769*
X02541Y02769*
X02546Y0277*
X0255Y02771*
X02554Y02773*
X02558Y02775*
X02561Y02777*
X02565Y02779*
X02568Y02781*
X02572Y02784*
X02575Y02787*
X02578Y0279*
X0258Y02794*
X02583Y02797*
X02585Y02801*
X02587Y02805*
X02588Y02809*
X0259Y02813*
X02591Y02817*
X02591Y02821*
X02592Y02825*
X02592Y02829*
Y03853D02*
D01*
X02592Y03857*
X02591Y03862*
X02591Y03866*
X0259Y0387*
X02588Y03874*
X02587Y03878*
X02585Y03882*
X02583Y03885*
X0258Y03889*
X02578Y03892*
X02575Y03895*
X02572Y03898*
X02568Y03901*
X02565Y03904*
X02561Y03906*
X02558Y03908*
X02554Y0391*
X0255Y03911*
X02546Y03912*
X02541Y03913*
X02537Y03914*
X02533Y03914*
X02529*
X02525Y03914*
X0252Y03913*
X02516Y03912*
X02512Y03911*
X02508Y0391*
X02504Y03908*
X025Y03906*
X02497Y03904*
X02493Y03901*
X0249Y03898*
X02487Y03895*
X02484Y03892*
X02482Y03889*
X02479Y03885*
X02477Y03882*
X02475Y03878*
X02474Y03874*
X02472Y0387*
X02471Y03866*
X0247Y03862*
X0247Y03857*
X0247Y03853*
X0247Y03849*
X0247Y03845*
X02471Y0384*
X02472Y03836*
X02474Y03832*
X02475Y03828*
X02477Y03824*
X02479Y03821*
X02482Y03817*
X02484Y03814*
X02487Y03811*
X0249Y03808*
X02493Y03805*
X02497Y03802*
X025Y038*
X02504Y03798*
X02508Y03796*
X02512Y03795*
X02516Y03794*
X0252Y03793*
X02525Y03792*
X02529Y03792*
X02533*
X02537Y03792*
X02541Y03793*
X02546Y03794*
X0255Y03795*
X02554Y03796*
X02558Y03798*
X02561Y038*
X02565Y03802*
X02568Y03805*
X02572Y03808*
X02575Y03811*
X02578Y03814*
X0258Y03817*
X02583Y03821*
X02585Y03824*
X02587Y03828*
X02588Y03832*
X0259Y03836*
X02591Y0384*
X02591Y03845*
X02592Y03849*
X02592Y03853*
X0021D02*
D01*
X0021Y03857*
X00209Y03862*
X00209Y03866*
X00208Y0387*
X00206Y03874*
X00205Y03878*
X00203Y03882*
X00201Y03885*
X00198Y03889*
X00196Y03892*
X00193Y03895*
X0019Y03898*
X00187Y03901*
X00183Y03904*
X0018Y03906*
X00176Y03908*
X00172Y0391*
X00168Y03911*
X00164Y03912*
X0016Y03913*
X00155Y03914*
X00151Y03914*
X00147*
X00143Y03914*
X00138Y03913*
X00134Y03912*
X0013Y03911*
X00126Y0391*
X00122Y03908*
X00118Y03906*
X00115Y03904*
X00111Y03901*
X00108Y03898*
X00105Y03895*
X00102Y03892*
X001Y03889*
X00097Y03885*
X00095Y03882*
X00093Y03878*
X00092Y03874*
X0009Y0387*
X00089Y03866*
X00089Y03862*
X00088Y03857*
X00088Y03853*
X00088Y03849*
X00089Y03845*
X00089Y0384*
X0009Y03836*
X00092Y03832*
X00093Y03828*
X00095Y03824*
X00097Y03821*
X001Y03817*
X00102Y03814*
X00105Y03811*
X00108Y03808*
X00111Y03805*
X00115Y03802*
X00119Y038*
X00122Y03798*
X00126Y03796*
X0013Y03795*
X00134Y03794*
X00138Y03793*
X00143Y03792*
X00147Y03792*
X00151*
X00155Y03792*
X0016Y03793*
X00164Y03794*
X00168Y03795*
X00172Y03796*
X00176Y03798*
X0018Y038*
X00183Y03802*
X00187Y03805*
X0019Y03808*
X00193Y03811*
X00196Y03814*
X00198Y03817*
X00201Y03821*
X00203Y03824*
X00205Y03828*
X00206Y03832*
X00208Y03836*
X00209Y0384*
X00209Y03845*
X0021Y03849*
X0021Y03853*
Y02829D02*
D01*
X0021Y02834*
X00209Y02838*
X00209Y02842*
X00208Y02846*
X00206Y0285*
X00205Y02854*
X00203Y02858*
X00201Y02862*
X00198Y02865*
X00196Y02869*
X00193Y02872*
X0019Y02875*
X00187Y02878*
X00183Y0288*
X0018Y02882*
X00176Y02884*
X00172Y02886*
X00168Y02887*
X00164Y02889*
X0016Y0289*
X00155Y0289*
X00151Y0289*
X00147*
X00143Y0289*
X00138Y0289*
X00134Y02889*
X0013Y02887*
X00126Y02886*
X00122Y02884*
X00118Y02882*
X00115Y0288*
X00111Y02878*
X00108Y02875*
X00105Y02872*
X00102Y02869*
X001Y02865*
X00097Y02862*
X00095Y02858*
X00093Y02854*
X00092Y0285*
X0009Y02846*
X00089Y02842*
X00089Y02838*
X00088Y02834*
X00088Y02829*
X00088Y02825*
X00089Y02821*
X00089Y02817*
X0009Y02813*
X00092Y02809*
X00093Y02805*
X00095Y02801*
X00097Y02797*
X001Y02794*
X00102Y0279*
X00105Y02787*
X00108Y02784*
X00111Y02781*
X00115Y02779*
X00119Y02777*
X00122Y02775*
X00126Y02773*
X0013Y02771*
X00134Y0277*
X00138Y02769*
X00143Y02769*
X00147Y02768*
X00151*
X00155Y02769*
X0016Y02769*
X00164Y0277*
X00168Y02771*
X00172Y02773*
X00176Y02775*
X0018Y02777*
X00183Y02779*
X00187Y02781*
X0019Y02784*
X00193Y02787*
X00196Y0279*
X00198Y02794*
X00201Y02797*
X00203Y02801*
X00205Y02805*
X00206Y02809*
X00208Y02813*
X00209Y02817*
X00209Y02821*
X0021Y02825*
X0021Y02829*
X06931Y02348D02*
Y02874D01*
X06427Y02348D02*
X06931D01*
X06427D02*
Y02874D01*
X06931*
X05778Y00689D02*
Y02689D01*
X03778Y00689D02*
X05778D01*
X03778D02*
Y02689D01*
X05778*
X06534Y03131D02*
Y03351D01*
X06364Y03131D02*
X06534D01*
X06364D02*
Y03351D01*
X06534*
X06067Y01388D02*
X06571D01*
Y01914*
X06067D02*
X06571D01*
X06067Y01388D02*
Y01914D01*
X02662Y02716D02*
Y03966D01*
X00018D02*
X02662D01*
X00018Y02716D02*
Y03966D01*
Y02716D02*
X02662D01*
X03543Y02183D02*
X03563D01*
X03553*
Y02243*
X03543Y02233*
X02108Y02408D02*
X02068D01*
X02108Y02448*
Y02458*
X02098Y02468*
X02078*
X02068Y02458*
X01668Y02233D02*
X01678Y02243D01*
X01698*
X01708Y02233*
Y02223*
X01698Y02213*
X01688*
X01698*
X01708Y02203*
Y02193*
X01698Y02183*
X01678*
X01668Y02193*
X02098Y00933D02*
Y00993D01*
X02068Y00963*
X02108*
X02402Y04126D02*
Y04106D01*
Y04116*
X02462*
X02452Y04126*
X03984Y03973D02*
X03964D01*
X03974*
Y03913*
X03984Y03923*
X03191Y02946D02*
Y02921D01*
X03196Y02916*
X03206*
X03211Y02921*
Y02946*
X03236Y02916D02*
Y02946D01*
X03221Y02931*
X03241*
X05251Y04134D02*
Y04164D01*
X05266*
X05271Y04159*
Y04149*
X05266Y04144*
X05251*
X05261D02*
X05271Y04134D01*
X05281Y04159D02*
X05286Y04164D01*
X05296*
X05301Y04159*
Y04154*
X05296Y04149*
X05291*
X05296*
X05301Y04144*
Y04139*
X05296Y04134*
X05286*
X05281Y04139*
X05331Y04164D02*
X05321Y04159D01*
X05311Y04149*
Y04139*
X05316Y04134*
X05326*
X05331Y04139*
Y04144*
X05326Y04149*
X05311*
X00589Y04037D02*
X00559D01*
Y04052*
X00564Y04057*
X00574*
X00579Y04052*
Y04037*
Y04047D02*
X00589Y04057D01*
Y04067D02*
Y04077D01*
Y04072*
X00559*
X00564Y04067*
X00559Y04112D02*
X00564Y04102D01*
X00574Y04092*
X00584*
X00589Y04097*
Y04107*
X00584Y04112*
X00579*
X00574Y04107*
Y04092*
X01013Y02264D02*
Y02294D01*
X01028*
X01033Y02289*
Y02279*
X01028Y02274*
X01013*
X01023D02*
X01033Y02264D01*
X01043D02*
X01053D01*
X01048*
Y02294*
X01043Y02289*
X01088Y02294D02*
X01068D01*
Y02279*
X01078Y02284*
X01083*
X01088Y02279*
Y02269*
X01083Y02264*
X01073*
X01068Y02269*
X00994Y01733D02*
Y01763D01*
X01009*
X01014Y01758*
Y01748*
X01009Y01743*
X00994*
X01004D02*
X01014Y01733D01*
X01024D02*
X01034D01*
X01029*
Y01763*
X01024Y01758*
X01063Y01733D02*
Y01763D01*
X01048Y01748*
X01068*
X02373Y03008D02*
Y03038D01*
X02388*
X02393Y03033*
Y03023*
X02388Y03018*
X02373*
X02383D02*
X02393Y03008D01*
X02403D02*
X02413D01*
X02408*
Y03038*
X02403Y03033*
X02428Y03038D02*
X02448D01*
Y03033*
X02428Y03013*
Y03008*
X02841Y03381D02*
Y03356D01*
X02846Y03351*
X02856*
X02861Y03356*
Y03381*
X02871Y03376D02*
X02876Y03381D01*
X02886*
X02891Y03376*
Y03371*
X02886Y03366*
X02881*
X02886*
X02891Y03361*
Y03356*
X02886Y03351*
X02876*
X02871Y03356*
X04137Y02522D02*
Y02497D01*
X04142Y02492*
X04152*
X04157Y02497*
Y02522*
X04167Y02492D02*
X04177D01*
X04172*
Y02522*
X04167Y02517*
X04192D02*
X04197Y02522D01*
X04207*
X04212Y02517*
Y02497*
X04207Y02492*
X04197*
X04192Y02497*
Y02517*
X04222Y02492D02*
Y02512D01*
X04232Y02522*
X04242Y02512*
Y02492*
Y02507*
X04222*
X04252Y02522D02*
Y02492D01*
X04272*
X04602Y04011D02*
Y03981D01*
X04617*
X04622Y03986*
Y03991*
X04617Y03996*
X04602*
X04617*
X04622Y04001*
Y04006*
X04617Y04011*
X04602*
X04632D02*
X04652D01*
X04642*
Y03981*
X04662D02*
X04672D01*
X04667*
Y04011*
X04662Y04006*
G54D15*
X02869Y03861D02*
D01*
X02869Y03862*
X02869Y03864*
X02869Y03866*
X02868Y03867*
X02868Y03869*
X02867Y03871*
X02866Y03872*
X02866Y03874*
X02865Y03875*
X02863Y03877*
X02862Y03878*
X02861Y03879*
X0286Y0388*
X02858Y03881*
X02857Y03882*
X02855Y03883*
X02854Y03884*
X02852Y03884*
X0285Y03885*
X02849Y03885*
X02847Y03885*
X02845Y03886*
X02843*
X02842Y03885*
X0284Y03885*
X02838Y03885*
X02837Y03884*
X02835Y03884*
X02833Y03883*
X02832Y03882*
X0283Y03881*
X02829Y0388*
X02828Y03879*
X02826Y03878*
X02825Y03877*
X02824Y03875*
X02823Y03874*
X02822Y03872*
X02822Y03871*
X02821Y03869*
X0282Y03867*
X0282Y03866*
X0282Y03864*
X02819Y03862*
X02819Y03861*
X02819Y03859*
X0282Y03857*
X0282Y03855*
X0282Y03854*
X02821Y03852*
X02822Y0385*
X02822Y03849*
X02823Y03847*
X02824Y03846*
X02825Y03845*
X02826Y03843*
X02828Y03842*
X02829Y03841*
X0283Y0384*
X02832Y03839*
X02833Y03838*
X02835Y03837*
X02837Y03837*
X02838Y03836*
X0284Y03836*
X02842Y03836*
X02843Y03836*
X02845*
X02847Y03836*
X02849Y03836*
X0285Y03836*
X02852Y03837*
X02854Y03837*
X02855Y03838*
X02857Y03839*
X02858Y0384*
X0286Y03841*
X02861Y03842*
X02862Y03843*
X02863Y03845*
X02865Y03846*
X02866Y03847*
X02866Y03849*
X02867Y0385*
X02868Y03852*
X02868Y03854*
X02869Y03855*
X02869Y03857*
X02869Y03859*
X02869Y03861*
X00929Y00706D02*
X00944D01*
X00929Y00734D02*
X00944D01*
X00602Y01931D02*
Y01974D01*
Y02458D02*
Y02501D01*
Y00883D02*
Y00927D01*
Y01411D02*
Y01454D01*
X05181Y04167D02*
X05196D01*
X05181Y04139D02*
X05196D01*
X0447Y03812D02*
Y03825D01*
X04401Y0385D02*
X04425D01*
X04356Y03812D02*
Y03825D01*
X00929Y01202D02*
X00944D01*
X00929Y0123D02*
X00944D01*
X02812Y02905D02*
X03056D01*
X02812Y03318D02*
X03056D01*
Y02905D02*
Y03318D01*
X02812Y02905D02*
Y03318D01*
X03513Y03679D02*
Y03718D01*
X03495Y03679D02*
X03513D01*
X03426D02*
Y03718D01*
Y03679D02*
X03444D01*
X01675Y04013D02*
Y0421D01*
X01801Y04013D02*
Y0421D01*
X01675D02*
X01801D01*
X01675Y04013D02*
X01801D01*
X06208Y03738D02*
X0633D01*
X06208Y03663D02*
X0633D01*
X06208Y03733D02*
Y03738D01*
X0633Y03733D02*
Y03738D01*
X06208Y03663D02*
Y03668D01*
X0633Y03663D02*
Y03668D01*
X02744Y03903D02*
Y04268D01*
X03544Y03903D02*
Y04268D01*
X02744D02*
X02906D01*
X03383D02*
X03544D01*
X03383Y03903D02*
X03544D01*
X02744D02*
X02906D01*
X04132Y02457D02*
X05522D01*
Y00857D02*
Y02457D01*
X04132Y00857D02*
X05522D01*
X04132D02*
Y02457D01*
X04584Y02812D02*
Y03957D01*
X05006D02*
X05234D01*
X04584D02*
X04812D01*
X05234Y02812D02*
Y03957D01*
X05006Y02812D02*
X05234D01*
X04584D02*
X04812D01*
X04909Y02691D02*
Y02715D01*
X04897Y02703D02*
X04921D01*
X00903Y00983D02*
Y0103D01*
X01186Y00983D02*
Y0103D01*
X00903Y00782D02*
Y00828D01*
X01186Y00782D02*
Y00828D01*
X00903Y0103D02*
X01186D01*
X00903Y00782D02*
X01186D01*
X05898Y03738D02*
X0602D01*
X05898Y03663D02*
X0602D01*
X05898Y03733D02*
Y03738D01*
X0602Y03733D02*
Y03738D01*
X05898Y03663D02*
Y03668D01*
X0602Y03663D02*
Y03668D01*
X06335Y03528D02*
Y03533D01*
X06213Y03528D02*
Y03533D01*
X06335Y03598D02*
Y03603D01*
X06213Y03598D02*
Y03603D01*
Y03528D02*
X06335D01*
X06213Y03603D02*
X06335D01*
X02878Y03679D02*
Y03718D01*
X0286Y03679D02*
X02878D01*
X02791D02*
Y03718D01*
Y03679D02*
X02809D01*
X02763D02*
Y03718D01*
X02745Y03679D02*
X02763D01*
X02676D02*
Y03718D01*
Y03679D02*
X02694D01*
X03288D02*
Y03718D01*
X0327Y03679D02*
X03288D01*
X03201D02*
Y03718D01*
Y03679D02*
X03219D01*
X00903Y01832D02*
X01186D01*
X00903Y0208D02*
X01186D01*
Y01832D02*
Y01878D01*
X00903Y01832D02*
Y01878D01*
X01186Y02033D02*
Y0208D01*
X00903Y02033D02*
Y0208D01*
Y02357D02*
X01186D01*
X00903Y02605D02*
X01186D01*
Y02357D02*
Y02403D01*
X00903Y02357D02*
Y02403D01*
X01186Y02558D02*
Y02605D01*
X00903Y02558D02*
Y02605D01*
Y01508D02*
Y01555D01*
X01186Y01508D02*
Y01555D01*
X00903Y01307D02*
Y01353D01*
X01186Y01307D02*
Y01353D01*
X00903Y01555D02*
X01186D01*
X00903Y01307D02*
X01186D01*
X03816Y03672D02*
Y03869D01*
X03942Y03672D02*
Y03869D01*
X03816D02*
X03942D01*
X03816Y03672D02*
X03942D01*
X0136Y04104D02*
Y0412D01*
X01332Y04104D02*
Y0412D01*
Y04D02*
Y04015D01*
X0136Y04D02*
Y04015D01*
X02165Y04037D02*
Y04053D01*
X02137Y04037D02*
Y04053D01*
X02226Y04037D02*
Y04053D01*
X02198Y04037D02*
Y04053D01*
X02401Y02921D02*
Y02937D01*
X02374Y02921D02*
Y02937D01*
X00922Y01733D02*
X00937D01*
X00922Y0176D02*
X00937D01*
X00933Y02261D02*
X00948D01*
X00933Y02289D02*
X00948D01*
G54D16*
X06127Y03741D02*
D01*
X06127Y03741*
X06127Y03742*
X06127Y03742*
X06127Y03743*
X06127Y03743*
X06127Y03744*
X06126Y03744*
X06126Y03745*
X06126Y03745*
X06125Y03746*
X06125Y03746*
X06125Y03746*
X06124Y03747*
X06124Y03747*
X06123Y03747*
X06123Y03748*
X06122Y03748*
X06122Y03748*
X06121Y03748*
X06121Y03748*
X0612Y03748*
X0612Y03748*
X06119*
X06119Y03748*
X06118Y03748*
X06117Y03748*
X06117Y03748*
X06116Y03748*
X06116Y03748*
X06115Y03747*
X06115Y03747*
X06115Y03747*
X06114Y03746*
X06114Y03746*
X06113Y03746*
X06113Y03745*
X06113Y03745*
X06112Y03744*
X06112Y03744*
X06112Y03743*
X06112Y03743*
X06112Y03742*
X06112Y03742*
X06111Y03741*
X06111Y03741*
X06111Y0374*
X06112Y0374*
X06112Y03739*
X06112Y03738*
X06112Y03738*
X06112Y03737*
X06112Y03737*
X06113Y03736*
X06113Y03736*
X06113Y03736*
X06114Y03735*
X06114Y03735*
X06115Y03734*
X06115Y03734*
X06115Y03734*
X06116Y03734*
X06116Y03733*
X06117Y03733*
X06117Y03733*
X06118Y03733*
X06119Y03733*
X06119Y03733*
X0612*
X0612Y03733*
X06121Y03733*
X06121Y03733*
X06122Y03733*
X06122Y03733*
X06123Y03734*
X06123Y03734*
X06124Y03734*
X06124Y03734*
X06125Y03735*
X06125Y03735*
X06125Y03736*
X06126Y03736*
X06126Y03736*
X06126Y03737*
X06127Y03737*
X06127Y03738*
X06127Y03738*
X06127Y03739*
X06127Y0374*
X06127Y0374*
X06127Y03741*
G54D17*
X04177Y03583D02*
Y03623D01*
X02171Y03651D02*
Y03711D01*
X02247Y03651D02*
Y03711D01*
X04665Y04185D02*
Y04224D01*
X02492Y0416D02*
Y04235D01*
X02172Y0416D02*
Y04235D01*
X04059Y04098D02*
Y04173D01*
X03684Y04098D02*
Y04173D01*
X06994Y03306D02*
X07009D01*
Y03296D02*
Y03306D01*
X06994Y03156D02*
X07009D01*
Y03166*
X06659Y03156D02*
X06674D01*
X06659Y03306D02*
X06674D01*
X06659Y03156D02*
Y03306D01*
X07009Y03166D02*
Y03296D01*
X06779Y03156D02*
X06889D01*
X06779Y03306D02*
X06889D01*
X06684Y03181D02*
Y03281D01*
X03319Y03706D02*
X03379D01*
X03504Y02777D02*
Y02816D01*
X05831Y03464D02*
Y04224D01*
X05396Y03464D02*
X05831D01*
X05396D02*
Y03982D01*
Y04224D02*
X05831D01*
X05396Y03982D02*
Y04224D01*
X06062Y03536D02*
Y03575D01*
X04301Y02786D02*
Y02846D01*
X04377Y02786D02*
Y02846D01*
X04011Y03036D02*
Y03086D01*
X04067Y03036D02*
Y03086D01*
X02093Y04007D02*
Y04307D01*
X01993Y04007D02*
X02093D01*
X01993D02*
Y04307D01*
X02093*
X05746Y03399D02*
X05806D01*
X05746Y03323D02*
X05806D01*
X06441Y02246D02*
Y02296D01*
X06497Y02246D02*
Y02296D01*
X06491Y01961D02*
Y02011D01*
X06547Y01961D02*
Y02011D01*
X06296Y02116D02*
Y02176D01*
X06372Y02116D02*
Y02176D01*
X06697Y02101D02*
Y02161D01*
X06621Y02101D02*
Y02161D01*
X06313Y02828D02*
Y02888D01*
X06237Y02828D02*
Y02888D01*
X064Y02828D02*
Y02888D01*
X06324Y02828D02*
Y02888D01*
X06634Y01459D02*
X06694D01*
X06634Y01383D02*
X06694D01*
X06634Y01569D02*
X06694D01*
X06634Y01493D02*
X06694D01*
X04066Y03776D02*
Y03836D01*
X04142Y03776D02*
Y03836D01*
X04166Y03781D02*
Y03831D01*
X04222Y03781D02*
Y03831D01*
X06444Y03109D02*
X06504D01*
X06444Y03033D02*
X06504D01*
X02601Y03541D02*
Y03601D01*
X02677Y03541D02*
Y03601D01*
X03664Y00688D02*
X03724D01*
X03664Y00764D02*
X03724D01*
X03731Y03123D02*
Y03183D01*
X03655Y03123D02*
Y03183D01*
X0366Y03273D02*
Y03323D01*
X03716Y03273D02*
Y03323D01*
X0673Y02116D02*
X06769D01*
X06215Y02156D02*
X06254D01*
X06869Y01796D02*
Y01835D01*
X06763Y01799D02*
Y01838D01*
X06338Y0244D02*
Y0248D01*
X0698Y01905D02*
X07019D01*
X05984Y02362D02*
X06023D01*
X02914Y03706D02*
X02974D01*
X03014D02*
X03074D01*
X03114D02*
X03174D01*
X02127Y02652D02*
X02166D01*
X04139Y03681D02*
Y0372D01*
X05188Y04188D02*
Y04228D01*
X04665Y04129D02*
Y04169D01*
X06103Y02461D02*
X06142D01*
X01914Y04102D02*
X01953D01*
X0167Y04301D02*
X0172D01*
X0167Y04245D02*
X0172D01*
X01807Y04314D02*
X01867D01*
X01807Y04238D02*
X01867D01*
X06576Y03271D02*
Y03321D01*
X06632Y03271D02*
Y03321D01*
Y03136D02*
Y03186D01*
X06576Y03136D02*
Y03186D01*
X04214Y03208D02*
X04274D01*
X04214Y03284D02*
X04274D01*
X04026Y02786D02*
Y02846D01*
X04102Y02786D02*
Y02846D01*
X03921Y02786D02*
Y02846D01*
X03997Y02786D02*
Y02846D01*
X04196Y02786D02*
Y02846D01*
X04272Y02786D02*
Y02846D01*
X01507Y04003D02*
Y04303D01*
X01407Y04003D02*
X01507D01*
X01407D02*
Y04303D01*
X01507*
G54D18*
X00379Y02301D02*
Y02381D01*
X00099Y02301D02*
X00379D01*
Y02581D02*
Y02661D01*
X00099D02*
X00379D01*
X00069Y02301D02*
X00099D01*
X00029Y02341D02*
X00069Y02301D01*
Y02661D02*
X00099D01*
X00029Y02621D02*
X00069Y02661D01*
X00379Y01776D02*
Y01856D01*
X00099Y01776D02*
X00379D01*
Y02056D02*
Y02136D01*
X00099D02*
X00379D01*
X00069Y01776D02*
X00099D01*
X00029Y01816D02*
X00069Y01776D01*
Y02136D02*
X00099D01*
X00029Y02096D02*
X00069Y02136D01*
X00379Y01251D02*
Y01331D01*
X00099Y01251D02*
X00379D01*
Y01531D02*
Y01611D01*
X00099D02*
X00379D01*
X00069Y01251D02*
X00099D01*
X00029Y01291D02*
X00069Y01251D01*
Y01611D02*
X00099D01*
X00029Y01571D02*
X00069Y01611D01*
X00379Y00726D02*
Y00806D01*
X00099Y00726D02*
X00379D01*
Y01006D02*
Y01086D01*
X00099D02*
X00379D01*
X00069Y00726D02*
X00099D01*
X00029Y00766D02*
X00069Y00726D01*
Y01086D02*
X00099D01*
X00029Y01046D02*
X00069Y01086D01*
G54D19*
X0155Y00814D02*
Y02586D01*
X03715Y00814D02*
Y02586D01*
X0155Y00814D02*
X03715D01*
X0155Y02586D02*
X03715D01*
G54D20*
X03492Y01281D02*
Y01307D01*
Y01281D02*
X03516D01*
Y01259D02*
Y01281D01*
Y01259D02*
X03626D01*
Y01281*
X0365*
Y01307*
X03492Y02097D02*
Y02123D01*
X03516*
Y02145*
X03626*
Y02123D02*
Y02145D01*
Y02123D02*
X0365D01*
Y02097D02*
Y02123D01*
X02175Y02516D02*
X02201D01*
X02175Y02492D02*
Y02516D01*
X02153Y02492D02*
X02175D01*
X02153Y02382D02*
Y02492D01*
Y02382D02*
X02175D01*
Y02358D02*
Y02382D01*
Y02358D02*
X02201D01*
X02991Y02516D02*
X03017D01*
Y02492D02*
Y02516D01*
Y02492D02*
X03039D01*
Y02382D02*
Y02492D01*
X03017Y02382D02*
X03039D01*
X03017Y02358D02*
Y02382D01*
X02991Y02358D02*
X03017D01*
X01775Y02097D02*
Y02123D01*
X01751D02*
X01775D01*
X01751D02*
Y02145D01*
X01641D02*
X01751D01*
X01641Y02123D02*
Y02145D01*
X01617Y02123D02*
X01641D01*
X01617Y02097D02*
Y02123D01*
X01775Y01281D02*
Y01307D01*
X01751Y01281D02*
X01775D01*
X01751Y01259D02*
Y01281D01*
X01641Y01259D02*
X01751D01*
X01641D02*
Y01281D01*
X01617D02*
X01641D01*
X01617D02*
Y01307D01*
X02175Y01036D02*
X02201D01*
X02175Y01012D02*
Y01036D01*
X02153Y01012D02*
X02175D01*
X02153Y00902D02*
Y01012D01*
Y00902D02*
X02175D01*
Y00878D02*
Y00902D01*
Y00878D02*
X02201D01*
X02991Y01036D02*
X03017D01*
Y01012D02*
Y01036D01*
Y01012D02*
X03039D01*
Y00902D02*
Y01012D01*
X03017Y00902D02*
X03039D01*
X03017Y00878D02*
Y00902D01*
X02991Y00878D02*
X03017D01*
G54D21*
X06176Y02414D02*
X06333D01*
X06176Y02217D02*
X06388D01*
X06656Y01857D02*
X06813D01*
X066Y02054D02*
X06813D01*
G54D22*
X03274Y03162D02*
X03313D01*
X03508Y03438D02*
X03628D01*
Y03326D02*
Y03438D01*
Y03162D02*
Y03202D01*
X03589Y03162D02*
X03628D01*
X03274D02*
Y03202D01*
Y03399D02*
Y03438D01*
X03313*
X03404Y02852D02*
Y02872D01*
Y02852D02*
X03424D01*
X03544D02*
X03564D01*
Y02872*
Y03072D02*
Y03092D01*
X03544D02*
X03564D01*
X03404D02*
X03458D01*
X03404Y03029D02*
Y03092D01*
X04934Y04151D02*
Y04161D01*
Y04151D02*
X05114D01*
Y04161*
Y04251D02*
Y04261D01*
X04934D02*
X05114D01*
X04934Y04251D02*
Y04261D01*
X05909Y04205D02*
X06309D01*
Y03792D02*
Y04205D01*
X05909Y03792D02*
Y03837D01*
X06224Y03792D02*
X06309D01*
X05909Y04038D02*
Y04205D01*
Y03792D02*
X06019D01*
X07003Y03572D02*
Y04356D01*
X06444Y03529D02*
X07003D01*
X06444D02*
Y04356D01*
X04409Y04151D02*
Y04161D01*
Y04151D02*
X04589D01*
Y04161*
Y04251D02*
Y04261D01*
X04409D02*
X04589D01*
X04409Y04251D02*
Y04261D01*
G54D23*
X07003Y03529D02*
Y03572D01*
G54D24*
X00406Y02301D02*
Y02321D01*
X00416Y02331*
X00426Y02321*
Y02301*
Y02316*
X00406*
X00436Y02301D02*
Y02331D01*
X00456Y02301*
Y02331*
X00466Y02301D02*
X00476D01*
X00471*
Y02331*
X00466Y02326*
X00404Y01775D02*
Y01795D01*
X00414Y01805*
X00424Y01795*
Y01775*
Y0179*
X00404*
X00434Y01775D02*
Y01805D01*
X00454Y01775*
Y01805*
X00484Y01775D02*
X00464D01*
X00484Y01795*
Y018*
X00479Y01805*
X00469*
X00464Y018*
X00406Y01252D02*
Y01272D01*
X00416Y01282*
X00426Y01272*
Y01252*
Y01267*
X00406*
X00436Y01252D02*
Y01282D01*
X00456Y01252*
Y01282*
X00466Y01277D02*
X00471Y01282D01*
X00481*
X00486Y01277*
Y01272*
X00481Y01267*
X00476*
X00481*
X00486Y01262*
Y01257*
X00481Y01252*
X00471*
X00466Y01257*
X00404Y00728D02*
Y00748D01*
X00414Y00758*
X00424Y00748*
Y00728*
Y00743*
X00404*
X00434Y00728D02*
Y00758D01*
X00454Y00728*
Y00758*
X00479Y00728D02*
Y00758D01*
X00464Y00743*
X00484*
X00722Y00802D02*
X00712D01*
X00717*
Y00777*
X00712Y00772*
X00707*
X00702Y00777*
X00732Y00772D02*
X00742D01*
X00737*
Y00802*
X00732Y00797*
X00757D02*
X00762Y00802D01*
X00772*
X00777Y00797*
Y00777*
X00772Y00772*
X00762*
X00757Y00777*
Y00797*
X00719Y01329D02*
X00709D01*
X00714*
Y01304*
X00709Y01299*
X00704*
X00699Y01304*
X00729D02*
X00734Y01299D01*
X00744*
X00749Y01304*
Y01324*
X00744Y01329*
X00734*
X00729Y01324*
Y01319*
X00734Y01314*
X00749*
X00719Y02389D02*
X00709D01*
X00714*
Y02364*
X00709Y02359*
X00704*
X00699Y02364*
X00749Y02389D02*
X00739Y02384D01*
X00729Y02374*
Y02364*
X00734Y02359*
X00744*
X00749Y02364*
Y02369*
X00744Y02374*
X00729*
X00719Y01853D02*
X00709D01*
X00714*
Y01828*
X00709Y01823*
X00704*
X00699Y01828*
X00749Y01853D02*
X00729D01*
Y01838*
X00739Y01843*
X00744*
X00749Y01838*
Y01828*
X00744Y01823*
X00734*
X00729Y01828*
X04282Y03914D02*
Y03944D01*
X04297*
X04302Y03939*
Y03929*
X04297Y03924*
X04282*
X04292D02*
X04302Y03914D01*
X04312Y03939D02*
X04317Y03944D01*
X04327*
X04332Y03939*
Y03934*
X04327Y03929*
X04322*
X04327*
X04332Y03924*
Y03919*
X04327Y03914*
X04317*
X04312Y03919*
X04342Y03944D02*
X04362D01*
Y03939*
X04342Y03919*
Y03914*
X04273Y03757D02*
X04298D01*
X04303Y03762*
Y03772*
X04298Y03777*
X04273*
Y03787D02*
Y03807D01*
X04278*
X04298Y03787*
X04303*
X04513Y0392D02*
X04508Y03915D01*
Y03905*
X04513Y039*
X04533*
X04538Y03905*
Y03915*
X04533Y0392*
X04538Y0395D02*
Y0393D01*
X04518Y0395*
X04513*
X04508Y03945*
Y03935*
X04513Y0393*
X04508Y0398D02*
Y0396D01*
X04523*
X04518Y0397*
Y03975*
X04523Y0398*
X04533*
X04538Y03975*
Y03965*
X04533Y0396*
X03112Y02613D02*
X03107Y02608D01*
Y02598*
X03112Y02593*
X03132*
X03137Y02598*
Y02608*
X03132Y02613*
X03137Y02643D02*
Y02623D01*
X03117Y02643*
X03112*
X03107Y02638*
Y02628*
X03112Y02623*
X03137Y02668D02*
X03107D01*
X03122Y02653*
Y02673*
X03348Y02633D02*
X03343Y02628D01*
Y02618*
X03348Y02613*
X03368*
X03373Y02618*
Y02628*
X03368Y02633*
X03373Y02663D02*
Y02643D01*
X03353Y02663*
X03348*
X03343Y02658*
Y02648*
X03348Y02643*
Y02673D02*
X03343Y02678D01*
Y02688*
X03348Y02693*
X03353*
X03358Y02688*
Y02683*
Y02688*
X03363Y02693*
X03368*
X03373Y02688*
Y02678*
X03368Y02673*
X01953Y04005D02*
Y03995D01*
Y04*
X01978*
X01983Y03995*
Y0399*
X01978Y03985*
X01983Y04015D02*
X01953D01*
Y0403*
X01958Y04035*
X01968*
X01973Y0403*
Y04015*
X01983Y04065D02*
Y04045D01*
X01963Y04065*
X01958*
X01953Y0406*
Y0405*
X01958Y04045*
X01345Y04326D02*
X01335D01*
X0134*
Y04301*
X01335Y04296*
X0133*
X01325Y04301*
X01355Y04296D02*
Y04326D01*
X0137*
X01375Y04321*
Y04311*
X0137Y04306*
X01355*
X01385Y04296D02*
X01395D01*
X0139*
Y04326*
X01385Y04321*
X02429Y0408D02*
X02459D01*
Y04065*
X02454Y0406*
X02444*
X02439Y04065*
Y0408*
Y0407D02*
X02429Y0406D01*
Y0405D02*
Y0404D01*
Y04045*
X02459*
X02454Y0405*
Y04025D02*
X02459Y0402D01*
Y0401*
X02454Y04005*
X02449*
X02444Y0401*
Y04015*
Y0401*
X02439Y04005*
X02434*
X02429Y0401*
Y0402*
X02434Y04025*
X02378Y0408D02*
X02408D01*
Y04065*
X02403Y0406*
X02393*
X02388Y04065*
Y0408*
Y0407D02*
X02378Y0406D01*
Y0405D02*
Y0404D01*
Y04045*
X02408*
X02403Y0405*
X02378Y04005D02*
Y04025D01*
X02398Y04005*
X02403*
X02408Y0401*
Y0402*
X02403Y04025*
X04338Y02914D02*
X04333Y02909D01*
Y02899*
X04338Y02894*
X04358*
X04363Y02899*
Y02909*
X04358Y02914*
X04333Y02924D02*
Y02944D01*
X04338*
X04358Y02924*
X04363*
Y02974D02*
Y02954D01*
X04343Y02974*
X04338*
X04333Y02969*
Y02959*
X04338Y02954*
X04235Y02915D02*
X0423Y0291D01*
Y029*
X04235Y02895*
X04255*
X0426Y029*
Y0291*
X04255Y02915*
X0423Y02925D02*
Y02945D01*
X04235*
X04255Y02925*
X0426*
X04235Y02955D02*
X0423Y0296D01*
Y0297*
X04235Y02975*
X0424*
X04245Y0297*
Y02965*
Y0297*
X0425Y02975*
X04255*
X0426Y0297*
Y0296*
X04255Y02955*
X03787Y02818D02*
X03782Y02823D01*
X03772*
X03767Y02818*
Y02798*
X03772Y02793*
X03782*
X03787Y02798*
X03797Y02823D02*
X03817D01*
Y02818*
X03797Y02798*
Y02793*
X03842D02*
Y02823D01*
X03827Y02808*
X03847*
X04001Y02936D02*
X03996Y02941D01*
X03986*
X03981Y02936*
Y02916*
X03986Y02911*
X03996*
X04001Y02916*
X04011Y02941D02*
X04031D01*
Y02936*
X04011Y02916*
Y02911*
X04061Y02941D02*
X04041D01*
Y02926*
X04051Y02931*
X04056*
X04061Y02926*
Y02916*
X04056Y02911*
X04046*
X04041Y02916*
X03957Y03208D02*
X03952Y03203D01*
Y03193*
X03957Y03188*
X03977*
X03982Y03193*
Y03203*
X03977Y03208*
X03952Y03218D02*
Y03238D01*
X03957*
X03977Y03218*
X03982*
X03952Y03268D02*
X03957Y03258D01*
X03967Y03248*
X03977*
X03982Y03253*
Y03263*
X03977Y03268*
X03972*
X03967Y03263*
Y03248*
X04011Y03208D02*
X04006Y03203D01*
Y03193*
X04011Y03188*
X04031*
X04036Y03193*
Y03203*
X04031Y03208*
X04006Y03218D02*
Y03238D01*
X04011*
X04031Y03218*
X04036*
X04006Y03248D02*
Y03268D01*
X04011*
X04031Y03248*
X04036*
X04069Y03207D02*
X04064Y03202D01*
Y03192*
X04069Y03187*
X04089*
X04094Y03192*
Y03202*
X04089Y03207*
X04064Y03217D02*
Y03237D01*
X04069*
X04089Y03217*
X04094*
X04069Y03247D02*
X04064Y03252D01*
Y03262*
X04069Y03267*
X04074*
X04079Y03262*
X04084Y03267*
X04089*
X04094Y03262*
Y03252*
X04089Y03247*
X04084*
X04079Y03252*
X04074Y03247*
X04069*
X04079Y03252D02*
Y03262D01*
X04125Y03207D02*
X0412Y03202D01*
Y03192*
X04125Y03187*
X04145*
X0415Y03192*
Y03202*
X04145Y03207*
X0412Y03217D02*
Y03237D01*
X04125*
X04145Y03217*
X0415*
X04145Y03247D02*
X0415Y03252D01*
Y03262*
X04145Y03267*
X04125*
X0412Y03262*
Y03252*
X04125Y03247*
X0413*
X04135Y03252*
Y03267*
X04339Y0323D02*
X04334Y03225D01*
Y03215*
X04339Y0321*
X04359*
X04364Y03215*
Y03225*
X04359Y0323*
X04339Y0324D02*
X04334Y03245D01*
Y03255*
X04339Y0326*
X04344*
X04349Y03255*
X04354Y0326*
X04359*
X04364Y03255*
Y03245*
X04359Y0324*
X04354*
X04349Y03245*
X04344Y0324*
X04339*
X04349Y03245D02*
Y03255D01*
X04339Y0327D02*
X04334Y03275D01*
Y03285*
X04339Y0329*
X04359*
X04364Y03285*
Y03275*
X04359Y0327*
X04339*
X04389Y0323D02*
X04384Y03225D01*
Y03215*
X04389Y0321*
X04409*
X04414Y03215*
Y03225*
X04409Y0323*
X04389Y0324D02*
X04384Y03245D01*
Y03255*
X04389Y0326*
X04394*
X04399Y03255*
X04404Y0326*
X04409*
X04414Y03255*
Y03245*
X04409Y0324*
X04404*
X04399Y03245*
X04394Y0324*
X04389*
X04399Y03245D02*
Y03255D01*
X04414Y0327D02*
Y0328D01*
Y03275*
X04384*
X04389Y0327*
X04438Y03225D02*
X04433Y0322D01*
Y0321*
X04438Y03205*
X04458*
X04463Y0321*
Y0322*
X04458Y03225*
X04438Y03235D02*
X04433Y0324D01*
Y0325*
X04438Y03255*
X04443*
X04448Y0325*
X04453Y03255*
X04458*
X04463Y0325*
Y0324*
X04458Y03235*
X04453*
X04448Y0324*
X04443Y03235*
X04438*
X04448Y0324D02*
Y0325D01*
X04463Y03285D02*
Y03265D01*
X04443Y03285*
X04438*
X04433Y0328*
Y0327*
X04438Y03265*
X04487Y03185D02*
X04482Y0318D01*
Y0317*
X04487Y03165*
X04507*
X04512Y0317*
Y0318*
X04507Y03185*
X04487Y03195D02*
X04482Y032D01*
Y0321*
X04487Y03215*
X04492*
X04497Y0321*
X04502Y03215*
X04507*
X04512Y0321*
Y032*
X04507Y03195*
X04502*
X04497Y032*
X04492Y03195*
X04487*
X04497Y032D02*
Y0321D01*
X04487Y03225D02*
X04482Y0323D01*
Y0324*
X04487Y03245*
X04492*
X04497Y0324*
Y03235*
Y0324*
X04502Y03245*
X04507*
X04512Y0324*
Y0323*
X04507Y03225*
X042Y03341D02*
X04195Y03346D01*
X04185*
X0418Y03341*
Y03321*
X04185Y03316*
X04195*
X042Y03321*
X0421Y03341D02*
X04215Y03346D01*
X04225*
X0423Y03341*
Y03336*
X04225Y03331*
X0423Y03326*
Y03321*
X04225Y03316*
X04215*
X0421Y03321*
Y03326*
X04215Y03331*
X0421Y03336*
Y03341*
X04215Y03331D02*
X04225D01*
X04255Y03316D02*
Y03346D01*
X0424Y03331*
X0426*
X06644Y03394D02*
X06639Y03389D01*
Y03379*
X06644Y03374*
X06664*
X06669Y03379*
Y03389*
X06664Y03394*
X06644Y03404D02*
X06639Y03409D01*
Y03419*
X06644Y03424*
X06649*
X06654Y03419*
X06659Y03424*
X06664*
X06669Y03419*
Y03409*
X06664Y03404*
X06659*
X06654Y03409*
X06649Y03404*
X06644*
X06654Y03409D02*
Y03419D01*
X06639Y03453D02*
Y03434D01*
X06654*
X06649Y03443*
Y03448*
X06654Y03453*
X06664*
X06669Y03448*
Y03438*
X06664Y03434*
X06593Y03394D02*
X06588Y03389D01*
Y03379*
X06593Y03374*
X06613*
X06618Y03379*
Y03389*
X06613Y03394*
X06593Y03404D02*
X06588Y03409D01*
Y03419*
X06593Y03424*
X06598*
X06603Y03419*
X06608Y03424*
X06613*
X06618Y03419*
Y03409*
X06613Y03404*
X06608*
X06603Y03409*
X06598Y03404*
X06593*
X06603Y03409D02*
Y03419D01*
X06588Y03453D02*
X06593Y03443D01*
X06603Y03434*
X06613*
X06618Y03438*
Y03448*
X06613Y03453*
X06608*
X06603Y03448*
Y03434*
X0194Y04243D02*
X01935Y04238D01*
Y04228*
X0194Y04223*
X0196*
X01965Y04228*
Y04238*
X0196Y04243*
Y04253D02*
X01965Y04258D01*
Y04268*
X0196Y04273*
X0194*
X01935Y04268*
Y04258*
X0194Y04253*
X01945*
X0195Y04258*
Y04273*
X01965Y04283D02*
Y04293D01*
Y04288*
X01935*
X0194Y04283*
X01525Y04279D02*
X0152Y04284D01*
X0151*
X01505Y04279*
Y04259*
X0151Y04254*
X0152*
X01525Y04259*
X01535D02*
X0154Y04254D01*
X0155*
X01555Y04259*
Y04279*
X0155Y04284*
X0154*
X01535Y04279*
Y04274*
X0154Y04269*
X01555*
X01585Y04254D02*
X01565D01*
X01585Y04274*
Y04279*
X0158Y04284*
X0157*
X01565Y04279*
X03446Y02694D02*
Y02724D01*
X03461*
X03466Y02719*
Y02709*
X03461Y02704*
X03446*
X03456D02*
X03466Y02694D01*
X03491D02*
Y02724D01*
X03476Y02709*
X03496*
X03526Y02694D02*
X03506D01*
X03526Y02714*
Y02719*
X03521Y02724*
X03511*
X03506Y02719*
X01895Y04167D02*
Y04197D01*
X0191*
X01915Y04192*
Y04182*
X0191Y04177*
X01895*
X01905D02*
X01915Y04167D01*
X0194D02*
Y04197D01*
X01925Y04182*
X01945*
X01955Y04192D02*
X0196Y04197D01*
X0197*
X01975Y04192*
Y04187*
X0197Y04182*
X01965*
X0197*
X01975Y04177*
Y04172*
X0197Y04167*
X0196*
X01955Y04172*
X01541Y04025D02*
X01566D01*
X01571Y0403*
Y0404*
X01566Y04045*
X01541*
X01571Y04055D02*
Y04065D01*
Y0406*
X01541*
X01546Y04055*
X01541Y041D02*
X01546Y0409D01*
X01556Y0408*
X01566*
X01571Y04085*
Y04095*
X01566Y041*
X01561*
X01556Y04095*
Y0408*
X02535Y04188D02*
X02525D01*
X0253*
Y04163*
X02525Y04158*
X0252*
X02515Y04163*
X0256Y04158D02*
Y04188D01*
X02545Y04173*
X02565*
X06134Y02525D02*
X06104D01*
Y0254*
X06109Y02545*
X06119*
X06124Y0254*
Y02525*
Y02535D02*
X06134Y02545D01*
X06104Y02575D02*
Y02555D01*
X06119*
X06114Y02565*
Y0257*
X06119Y02575*
X06129*
X06134Y0257*
Y0256*
X06129Y02555*
X06951Y03391D02*
X06971Y03361D01*
Y03391D02*
X06951Y03361D01*
X06981D02*
X06991D01*
X06986*
Y03391*
X06981Y03386*
X03588Y02889D02*
Y02864D01*
X03593Y02859*
X03603*
X03608Y02864*
Y02889*
X03618Y02859D02*
X03628D01*
X03623*
Y02889*
X03618Y02884*
X03643D02*
X03648Y02889D01*
X03658*
X03663Y02884*
Y02879*
X03658Y02874*
X03653*
X03658*
X03663Y02869*
Y02864*
X03658Y02859*
X03648*
X03643Y02864*
X03159Y0342D02*
Y03395D01*
X03164Y0339*
X03174*
X03179Y03395*
Y0342*
X03189Y0339D02*
X03199D01*
X03194*
Y0342*
X03189Y03415*
X03214Y0339D02*
X03224D01*
X03219*
Y0342*
X03214Y03415*
X05652Y02744D02*
Y02719D01*
X05657Y02714*
X05667*
X05672Y02719*
Y02744*
X05682Y02714D02*
X05692D01*
X05687*
Y02744*
X05682Y02739*
X05707D02*
X05712Y02744D01*
X05722*
X05727Y02739*
Y02719*
X05722Y02714*
X05712*
X05707Y02719*
Y02739*
X02388Y03741D02*
Y03716D01*
X02393Y03711*
X02403*
X02408Y03716*
Y03741*
X02418Y03716D02*
X02423Y03711D01*
X02433*
X02438Y03716*
Y03736*
X02433Y03741*
X02423*
X02418Y03736*
Y03731*
X02423Y03726*
X02438*
X06368Y03415D02*
Y0339D01*
X06373Y03385*
X06383*
X06388Y0339*
Y03415*
X06398Y0341D02*
X06403Y03415D01*
X06413*
X06418Y0341*
Y03405*
X06413Y034*
X06418Y03395*
Y0339*
X06413Y03385*
X06403*
X06398Y0339*
Y03395*
X06403Y034*
X06398Y03405*
Y0341*
X06403Y034D02*
X06413D01*
X03841Y03633D02*
Y03608D01*
X03846Y03603*
X03856*
X03861Y03608*
Y03633*
X03891D02*
X03881Y03628D01*
X03871Y03618*
Y03608*
X03876Y03603*
X03886*
X03891Y03608*
Y03613*
X03886Y03618*
X03871*
X02629Y04251D02*
Y04226D01*
X02634Y04221*
X02644*
X02649Y04226*
Y04251*
X02679D02*
X02659D01*
Y04236*
X02669Y04241*
X02674*
X02679Y04236*
Y04226*
X02674Y04221*
X02664*
X02659Y04226*
X06013Y0226D02*
Y02235D01*
X06018Y0223*
X06028*
X06033Y02235*
Y0226*
X06063Y0223D02*
X06043D01*
X06063Y0225*
Y02255*
X06058Y0226*
X06048*
X06043Y02255*
X06561Y02106D02*
Y02081D01*
X06566Y02076*
X06576*
X06581Y02081*
Y02106*
X06591Y02076D02*
X06601D01*
X06596*
Y02106*
X06591Y02101*
X05411Y03411D02*
X05406Y03416D01*
X05396*
X05391Y03411*
Y03406*
X05396Y03401*
X05406*
X05411Y03396*
Y03391*
X05406Y03387*
X05396*
X05391Y03391*
X05421Y03416D02*
Y03387D01*
X05431Y03396*
X05441Y03387*
Y03416*
X05451Y03387D02*
X05461D01*
X05456*
Y03416*
X05451Y03411*
X04951Y04322D02*
X04946Y04327D01*
X04936*
X04931Y04322*
Y04317*
X04936Y04312*
X04946*
X04951Y04307*
Y04302*
X04946Y04297*
X04936*
X04931Y04302*
X04981Y04327D02*
X04971Y04322D01*
X04961Y04312*
Y04302*
X04966Y04297*
X04976*
X04981Y04302*
Y04307*
X04976Y04312*
X04961*
X04426Y04322D02*
X04421Y04327D01*
X04411*
X04406Y04322*
Y04317*
X04411Y04312*
X04421*
X04426Y04307*
Y04302*
X04421Y04297*
X04411*
X04406Y04302*
X04456Y04327D02*
X04436D01*
Y04312*
X04446Y04317*
X04451*
X04456Y04312*
Y04302*
X04451Y04297*
X04441*
X04436Y04302*
X04732Y04137D02*
Y04167D01*
X04747*
X04752Y04162*
Y04152*
X04747Y04147*
X04732*
X04742D02*
X04752Y04137D01*
X04762Y04162D02*
X04767Y04167D01*
X04777*
X04782Y04162*
Y04157*
X04777Y04152*
X04772*
X04777*
X04782Y04147*
Y04142*
X04777Y04137*
X04767*
X04762Y04142*
X04812Y04167D02*
X04792D01*
Y04152*
X04802Y04157*
X04807*
X04812Y04152*
Y04142*
X04807Y04137*
X04797*
X04792Y04142*
X05251Y04196D02*
Y04226D01*
X05266*
X05271Y04221*
Y04211*
X05266Y04206*
X05251*
X05261D02*
X05271Y04196D01*
X05281Y04221D02*
X05286Y04226D01*
X05296*
X05301Y04221*
Y04216*
X05296Y04211*
X05291*
X05296*
X05301Y04206*
Y04201*
X05296Y04196*
X05286*
X05281Y04201*
X05326Y04196D02*
Y04226D01*
X05311Y04211*
X05331*
X04732Y04192D02*
Y04222D01*
X04747*
X04752Y04217*
Y04207*
X04747Y04202*
X04732*
X04742D02*
X04752Y04192D01*
X04762Y04217D02*
X04767Y04222D01*
X04777*
X04782Y04217*
Y04212*
X04777Y04207*
X04772*
X04777*
X04782Y04202*
Y04197*
X04777Y04192*
X04767*
X04762Y04197*
X04792Y04217D02*
X04797Y04222D01*
X04807*
X04812Y04217*
Y04212*
X04807Y04207*
X04802*
X04807*
X04812Y04202*
Y04197*
X04807Y04192*
X04797*
X04792Y04197*
X01Y00708D02*
Y00738D01*
X01014*
X01019Y00733*
Y00723*
X01014Y00718*
X01*
X0101D02*
X01019Y00708D01*
X01029Y00733D02*
X01034Y00738D01*
X01044*
X01049Y00733*
Y00728*
X01044Y00723*
X01039*
X01044*
X01049Y00718*
Y00713*
X01044Y00708*
X01034*
X01029Y00713*
X01079Y00708D02*
X01059D01*
X01079Y00728*
Y00733*
X01074Y00738*
X01064*
X01059Y00733*
X01Y012D02*
Y0123D01*
X01014*
X01019Y01225*
Y01215*
X01014Y0121*
X01*
X0101D02*
X01019Y012D01*
X01029Y01225D02*
X01034Y0123D01*
X01044*
X01049Y01225*
Y0122*
X01044Y01215*
X01039*
X01044*
X01049Y0121*
Y01205*
X01044Y012*
X01034*
X01029Y01205*
X01059Y012D02*
X01069D01*
X01064*
Y0123*
X01059Y01225*
X01196Y04027D02*
X01166D01*
Y04042*
X01171Y04047*
X01181*
X01186Y04042*
Y04027*
Y04037D02*
X01196Y04047D01*
X01171Y04057D02*
X01166Y04062D01*
Y04072*
X01171Y04077*
X01176*
X01181Y04072*
Y04067*
Y04072*
X01186Y04077*
X01191*
X01196Y04072*
Y04062*
X01191Y04057*
X01171Y04087D02*
X01166Y04092D01*
Y04102*
X01171Y04107*
X01191*
X01196Y04102*
Y04092*
X01191Y04087*
X01171*
X00996Y04031D02*
X00966D01*
Y04046*
X00971Y04051*
X00981*
X00986Y04046*
Y04031*
Y04041D02*
X00996Y04051D01*
Y04081D02*
Y04061D01*
X00976Y04081*
X00971*
X00966Y04076*
Y04066*
X00971Y04061*
X00991Y04091D02*
X00996Y04096D01*
Y04106*
X00991Y04111*
X00971*
X00966Y04106*
Y04096*
X00971Y04091*
X00976*
X00981Y04096*
Y04111*
X00795Y04031D02*
X00765D01*
Y04046*
X0077Y04051*
X0078*
X00785Y04046*
Y04031*
Y04041D02*
X00795Y04051D01*
Y04081D02*
Y04061D01*
X00775Y04081*
X0077*
X00765Y04076*
Y04066*
X0077Y04061*
Y04091D02*
X00765Y04096D01*
Y04106*
X0077Y04111*
X00775*
X0078Y04106*
X00785Y04111*
X0079*
X00795Y04106*
Y04096*
X0079Y04091*
X00785*
X0078Y04096*
X00775Y04091*
X0077*
X0078Y04096D02*
Y04106D01*
X04216Y03688D02*
Y03718D01*
X04231*
X04236Y03713*
Y03703*
X04231Y03698*
X04216*
X04226D02*
X04236Y03688D01*
X04266D02*
X04246D01*
X04266Y03708*
Y03713*
X04261Y03718*
X04251*
X04246Y03713*
X04276Y03718D02*
X04296D01*
Y03713*
X04276Y03693*
Y03688*
X03637Y03692D02*
Y03722D01*
X03652*
X03657Y03717*
Y03707*
X03652Y03702*
X03637*
X03647D02*
X03657Y03692D01*
X03687D02*
X03667D01*
X03687Y03712*
Y03717*
X03682Y03722*
X03672*
X03667Y03717*
X03717Y03722D02*
X03707Y03717D01*
X03697Y03707*
Y03697*
X03702Y03692*
X03712*
X03717Y03697*
Y03702*
X03712Y03707*
X03697*
X03631Y0389D02*
Y0392D01*
X03646*
X03651Y03915*
Y03905*
X03646Y039*
X03631*
X03641D02*
X03651Y0389D01*
X03681D02*
X03661D01*
X03681Y0391*
Y03915*
X03676Y0392*
X03666*
X03661Y03915*
X03711Y0392D02*
X03691D01*
Y03905*
X03701Y0391*
X03706*
X03711Y03905*
Y03895*
X03706Y0389*
X03696*
X03691Y03895*
X03016Y00537D02*
X02986D01*
Y00552*
X02991Y00557*
X03001*
X03006Y00552*
Y00537*
Y00547D02*
X03016Y00557D01*
Y00587D02*
Y00567D01*
X02996Y00587*
X02991*
X02986Y00582*
Y00572*
X02991Y00567*
X03016Y00612D02*
X02986D01*
X03001Y00597*
Y00617*
X02468Y0054D02*
X02438D01*
Y00555*
X02443Y0056*
X02453*
X02458Y00555*
Y0054*
Y0055D02*
X02468Y0056D01*
Y0059D02*
Y0057D01*
X02448Y0059*
X02443*
X02438Y00585*
Y00575*
X02443Y0057*
Y006D02*
X02438Y00605D01*
Y00615*
X02443Y0062*
X02448*
X02453Y00615*
Y0061*
Y00615*
X02458Y0062*
X02463*
X02468Y00615*
Y00605*
X02463Y006*
X02102Y02614D02*
X02072D01*
Y02629*
X02077Y02634*
X02087*
X02092Y02629*
Y02614*
Y02624D02*
X02102Y02634D01*
Y02664D02*
Y02644D01*
X02082Y02664*
X02077*
X02072Y02659*
Y02649*
X02077Y02644*
X02102Y02694D02*
Y02674D01*
X02082Y02694*
X02077*
X02072Y02689*
Y02679*
X02077Y02674*
X03362Y03551D02*
X03332D01*
Y03566*
X03337Y03571*
X03347*
X03352Y03566*
Y03551*
Y03561D02*
X03362Y03571D01*
Y03601D02*
Y03581D01*
X03342Y03601*
X03337*
X03332Y03596*
Y03586*
X03337Y03581*
X03362Y03611D02*
Y03621D01*
Y03616*
X03332*
X03337Y03611*
X03168Y0351D02*
X03138D01*
Y03525*
X03143Y0353*
X03153*
X03158Y03525*
Y0351*
Y0352D02*
X03168Y0353D01*
Y0356D02*
Y0354D01*
X03148Y0356*
X03143*
X03138Y03555*
Y03545*
X03143Y0354*
Y0357D02*
X03138Y03575D01*
Y03585*
X03143Y0359*
X03163*
X03168Y03585*
Y03575*
X03163Y0357*
X03143*
X03066Y03513D02*
X03036D01*
Y03528*
X03041Y03533*
X03051*
X03056Y03528*
Y03513*
Y03523D02*
X03066Y03533D01*
Y03543D02*
Y03553D01*
Y03548*
X03036*
X03041Y03543*
X03061Y03568D02*
X03066Y03573D01*
Y03583*
X03061Y03588*
X03041*
X03036Y03583*
Y03573*
X03041Y03568*
X03046*
X03051Y03573*
Y03588*
X02972Y03513D02*
X02942D01*
Y03528*
X02947Y03533*
X02957*
X02962Y03528*
Y03513*
Y03523D02*
X02972Y03533D01*
Y03543D02*
Y03553D01*
Y03548*
X02942*
X02947Y03543*
Y03568D02*
X02942Y03573D01*
Y03583*
X02947Y03588*
X02952*
X02957Y03583*
X02962Y03588*
X02967*
X02972Y03583*
Y03573*
X02967Y03568*
X02962*
X02957Y03573*
X02952Y03568*
X02947*
X02957Y03573D02*
Y03583D01*
X06015Y02457D02*
X05985D01*
Y02472*
X0599Y02477*
X06*
X06005Y02472*
Y02457*
Y02467D02*
X06015Y02477D01*
X0601Y02487D02*
X06015Y02492D01*
Y02502*
X0601Y02507*
X0599*
X05985Y02502*
Y02492*
X0599Y02487*
X05995*
X06Y02492*
Y02507*
X07011Y01964D02*
X06981D01*
Y01979*
X06986Y01984*
X06996*
X07001Y01979*
Y01964*
Y01974D02*
X07011Y01984D01*
X06986Y01994D02*
X06981Y01999D01*
Y02009*
X06986Y02014*
X06991*
X06996Y02009*
X07001Y02014*
X07006*
X07011Y02009*
Y01999*
X07006Y01994*
X07001*
X06996Y01999*
X06991Y01994*
X06986*
X06996Y01999D02*
Y02009D01*
X06181Y0245D02*
Y0248D01*
X06196*
X06201Y02475*
Y02465*
X06196Y0246*
X06181*
X06191D02*
X06201Y0245D01*
X06211Y0248D02*
X06231D01*
Y02475*
X06211Y02455*
Y0245*
X0663Y01809D02*
Y01839D01*
X06645*
X06649Y01834*
Y01824*
X06645Y01819*
X0663*
X0664D02*
X06649Y01809D01*
X06679Y01839D02*
X06669Y01834D01*
X06659Y01824*
Y01814*
X06664Y01809*
X06674*
X06679Y01814*
Y01819*
X06674Y01824*
X06659*
X06845Y0175D02*
Y01779D01*
X0686*
X06865Y01774*
Y01764*
X0686Y0176*
X06845*
X06855D02*
X06865Y0175D01*
X0689D02*
Y01779D01*
X06875Y01764*
X06895*
X06248Y02043D02*
X06218D01*
Y02058*
X06223Y02063*
X06233*
X06238Y02058*
Y02043*
Y02053D02*
X06248Y02063D01*
X06223Y02073D02*
X06218Y02078D01*
Y02088*
X06223Y02093*
X06228*
X06233Y02088*
Y02083*
Y02088*
X06238Y02093*
X06243*
X06248Y02088*
Y02078*
X06243Y02073*
X06766Y02174D02*
X06736D01*
Y02189*
X06741Y02194*
X06751*
X06756Y02189*
Y02174*
Y02184D02*
X06766Y02194D01*
Y02224D02*
Y02204D01*
X06746Y02224*
X06741*
X06736Y02219*
Y02209*
X06741Y02204*
X04051Y0359D02*
Y0362D01*
X04066*
X04071Y03615*
Y03605*
X04066Y036*
X04051*
X04061D02*
X04071Y0359D01*
X04081D02*
X04091D01*
X04086*
Y0362*
X04081Y03615*
X01556Y02618D02*
Y02648D01*
X01571*
X01576Y02643*
Y02633*
X01571Y02628*
X01556*
X01586Y02618D02*
X01596D01*
X01591*
Y02648*
X01586Y02643*
X06866Y02939D02*
Y02909D01*
X06886*
X06916D02*
X06896D01*
X06916Y02929*
Y02934*
X06911Y02939*
X06901*
X06896Y02934*
X05973Y01899D02*
Y01869D01*
X05993*
X06003D02*
X06013D01*
X06008*
Y01899*
X06003Y01894*
X04136Y04266D02*
X04126D01*
X04131*
Y04241*
X04126Y04236*
X04121*
X04116Y04241*
X04146Y04261D02*
X04151Y04266D01*
X04161*
X04166Y04261*
Y04256*
X04161Y04251*
X04156*
X04161*
X04166Y04246*
Y04241*
X04161Y04236*
X04151*
X04146Y04241*
X06951Y03499D02*
X06941D01*
X06946*
Y03474*
X06941Y03469*
X06936*
X06931Y03474*
X06981Y03469D02*
X06961D01*
X06981Y03489*
Y03494*
X06976Y03499*
X06966*
X06961Y03494*
X06351Y04188D02*
X06341D01*
X06346*
Y04163*
X06341Y04158*
X06336*
X06331Y04163*
X06361Y04158D02*
X06371D01*
X06366*
Y04188*
X06361Y04183*
X04144Y02907D02*
Y02887D01*
X04159*
Y02897*
Y02887*
X04174*
X04144Y02917D02*
X04174D01*
Y02932*
X04169Y02937*
X04164*
X04159Y02932*
Y02917*
Y02932*
X04154Y02937*
X04149*
X04144Y02932*
Y02917*
X04149Y02947D02*
X04144Y02952D01*
Y02962*
X04149Y02967*
X04154*
X04159Y02962*
Y02957*
Y02962*
X04164Y02967*
X04169*
X04174Y02962*
Y02952*
X04169Y02947*
X04496Y02854D02*
Y02834D01*
X04511*
Y02844*
Y02834*
X04526*
X04496Y02864D02*
X04526D01*
Y02879*
X04521Y02884*
X04516*
X04511Y02879*
Y02864*
Y02879*
X04506Y02884*
X04501*
X04496Y02879*
Y02864*
X04526Y02914D02*
Y02894D01*
X04506Y02914*
X04501*
X04496Y02909*
Y02899*
X04501Y02894*
X06051Y03624D02*
X06031D01*
Y03609*
X06041*
X06031*
Y03594*
X06061D02*
X06071D01*
X06066*
Y03624*
X06061Y03619*
X00881Y01101D02*
Y01071D01*
X00896*
X00901Y01076*
Y01096*
X00896Y01101*
X00881*
X00911Y01071D02*
X00921D01*
X00916*
Y01101*
X00911Y01096*
X00936D02*
X00941Y01101D01*
X00951*
X00956Y01096*
Y01091*
X00951Y01086*
X00956Y01081*
Y01076*
X00951Y01071*
X00941*
X00936Y01076*
Y01081*
X00941Y01086*
X00936Y01091*
Y01096*
X00941Y01086D02*
X00951D01*
X00881Y01626D02*
Y01596D01*
X00896*
X00901Y01601*
Y01621*
X00896Y01626*
X00881*
X00911Y01596D02*
X00921D01*
X00916*
Y01626*
X00911Y01621*
X00936Y01626D02*
X00956D01*
Y01621*
X00936Y01601*
Y01596*
X00881Y02676D02*
Y02646D01*
X00896*
X00901Y02651*
Y02671*
X00896Y02676*
X00881*
X00911Y02646D02*
X00921D01*
X00916*
Y02676*
X00911Y02671*
X00956Y02676D02*
X00946Y02671D01*
X00936Y02661*
Y02651*
X00941Y02646*
X00951*
X00956Y02651*
Y02656*
X00951Y02661*
X00936*
X00881Y02151D02*
Y02121D01*
X00896*
X00901Y02126*
Y02146*
X00896Y02151*
X00881*
X00911Y02121D02*
X00921D01*
X00916*
Y02151*
X00911Y02146*
X00956Y02151D02*
X00936D01*
Y02136*
X00946Y02141*
X00951*
X00956Y02136*
Y02126*
X00951Y02121*
X00941*
X00936Y02126*
X01162Y04167D02*
X01192D01*
Y04182*
X01187Y04187*
X01167*
X01162Y04182*
Y04167*
X01192Y04197D02*
Y04207D01*
Y04202*
X01162*
X01167Y04197*
X01192Y04237D02*
X01162D01*
X01177Y04222*
Y04242*
X0096Y04164D02*
X0099D01*
Y04179*
X00985Y04184*
X00965*
X0096Y04179*
Y04164*
X0099Y04194D02*
Y04204D01*
Y04199*
X0096*
X00965Y04194*
Y04219D02*
X0096Y04224D01*
Y04234*
X00965Y04239*
X0097*
X00975Y04234*
Y04229*
Y04234*
X0098Y04239*
X00985*
X0099Y04234*
Y04224*
X00985Y04219*
X00764Y04168D02*
X00794D01*
Y04183*
X00789Y04188*
X00769*
X00764Y04183*
Y04168*
X00794Y04198D02*
Y04208D01*
Y04203*
X00764*
X00769Y04198*
X00794Y04243D02*
Y04223D01*
X00774Y04243*
X00769*
X00764Y04238*
Y04228*
X00769Y04223*
X00561Y04178D02*
X00591D01*
Y04193*
X00586Y04198*
X00566*
X00561Y04193*
Y04178*
X00591Y04208D02*
Y04218D01*
Y04213*
X00561*
X00566Y04208*
X00591Y04233D02*
Y04243D01*
Y04238*
X00561*
X00566Y04233*
X03572Y03614D02*
X03602D01*
Y03629*
X03597Y03634*
X03577*
X03572Y03629*
Y03614*
X03602Y03644D02*
Y03654D01*
Y03649*
X03572*
X03577Y03644*
Y03669D02*
X03572Y03674D01*
Y03684*
X03577Y03689*
X03597*
X03602Y03684*
Y03674*
X03597Y03669*
X03577*
X03572Y03956D02*
X03602D01*
Y03971*
X03597Y03976*
X03577*
X03572Y03971*
Y03956*
X03597Y03986D02*
X03602Y03991D01*
Y04001*
X03597Y04006*
X03577*
X03572Y04001*
Y03991*
X03577Y03986*
X03582*
X03587Y03991*
Y04006*
X03463Y03797D02*
X03493D01*
Y03812*
X03488Y03817*
X03468*
X03463Y03812*
Y03797*
X03468Y03827D02*
X03463Y03832D01*
Y03842*
X03468Y03847*
X03473*
X03478Y03842*
X03483Y03847*
X03488*
X03493Y03842*
Y03832*
X03488Y03827*
X03483*
X03478Y03832*
X03473Y03827*
X03468*
X03478Y03832D02*
Y03842D01*
X03229Y03511D02*
X03259D01*
Y03526*
X03254Y03531*
X03234*
X03229Y03526*
Y03511*
Y03541D02*
Y03561D01*
X03234*
X03254Y03541*
X03259*
X02705Y03852D02*
Y03822D01*
X0272*
X02725Y03827*
Y03847*
X0272Y03852*
X02705*
X02755D02*
X02745Y03847D01*
X02735Y03837*
Y03827*
X0274Y03822*
X0275*
X02755Y03827*
Y03832*
X0275Y03837*
X02735*
X02865Y03548D02*
X02895D01*
Y03563*
X0289Y03568*
X0287*
X02865Y03563*
Y03548*
Y03598D02*
Y03578D01*
X0288*
X02875Y03588*
Y03593*
X0288Y03598*
X0289*
X02895Y03593*
Y03583*
X0289Y03578*
X04389Y0362D02*
Y0359D01*
X04404*
X04409Y03595*
Y03615*
X04404Y0362*
X04389*
X04434Y0359D02*
Y0362D01*
X04419Y03605*
X04439*
X06371Y03681D02*
X06401D01*
Y03696*
X06396Y03701*
X06376*
X06371Y03696*
Y03681*
X06376Y03711D02*
X06371Y03716D01*
Y03726*
X06376Y03731*
X06381*
X06386Y03726*
Y03721*
Y03726*
X06391Y03731*
X06396*
X06401Y03726*
Y03716*
X06396Y03711*
X06379Y03543D02*
X06409D01*
Y03558*
X06404Y03563*
X06384*
X06379Y03558*
Y03543*
X06409Y03593D02*
Y03573D01*
X06389Y03593*
X06384*
X06379Y03588*
Y03578*
X06384Y03573*
X0606Y03685D02*
X0609D01*
Y037*
X06085Y03705*
X06065*
X0606Y037*
Y03685*
X0609Y03715D02*
Y03725D01*
Y0372*
X0606*
X06065Y03715*
X03685Y03415D02*
X0368Y0342D01*
X0367*
X03665Y03415*
Y03395*
X0367Y0339*
X0368*
X03685Y03395*
X03715Y0342D02*
X03705Y03415D01*
X03695Y03405*
Y03395*
X037Y0339*
X0371*
X03715Y03395*
Y034*
X0371Y03405*
X03695*
X03725Y0342D02*
X03745D01*
Y03415*
X03725Y03395*
Y0339*
X03758Y0296D02*
X03753Y02955D01*
Y02945*
X03758Y0294*
X03778*
X03783Y02945*
Y02955*
X03778Y0296*
X03753Y0299D02*
X03758Y0298D01*
X03768Y0297*
X03778*
X03783Y02975*
Y02985*
X03778Y0299*
X03773*
X03768Y02985*
Y0297*
X03753Y0302D02*
X03758Y0301D01*
X03768Y03*
X03778*
X03783Y03005*
Y03015*
X03778Y0302*
X03773*
X03768Y03015*
Y03*
X03683Y02964D02*
X03678Y02959D01*
Y02949*
X03683Y02944*
X03703*
X03708Y02949*
Y02959*
X03703Y02964*
X03678Y02994D02*
X03683Y02984D01*
X03693Y02974*
X03703*
X03708Y02979*
Y02989*
X03703Y02994*
X03698*
X03693Y02989*
Y02974*
X03678Y03024D02*
Y03004D01*
X03693*
X03688Y03014*
Y03019*
X03693Y03024*
X03703*
X03708Y03019*
Y03009*
X03703Y03004*
X03523Y00666D02*
X03518Y00671D01*
X03508*
X03503Y00666*
Y00646*
X03508Y00641*
X03518*
X03523Y00646*
X03553Y00671D02*
X03543Y00666D01*
X03533Y00656*
Y00646*
X03538Y00641*
X03548*
X03553Y00646*
Y00651*
X03548Y00656*
X03533*
X03563Y00666D02*
X03568Y00671D01*
X03578*
X03583Y00666*
Y00661*
X03578Y00656*
X03573*
X03578*
X03583Y00651*
Y00646*
X03578Y00641*
X03568*
X03563Y00646*
X03523Y00741D02*
X03518Y00746D01*
X03508*
X03503Y00741*
Y00721*
X03508Y00716*
X03518*
X03523Y00721*
X03553Y00746D02*
X03543Y00741D01*
X03533Y00731*
Y00721*
X03538Y00716*
X03548*
X03553Y00721*
Y00726*
X03548Y00731*
X03533*
X03583Y00716D02*
X03563D01*
X03583Y00736*
Y00741*
X03578Y00746*
X03568*
X03563Y00741*
X02766Y03401D02*
X02761Y03396D01*
Y03386*
X02766Y03381*
X02786*
X02791Y03386*
Y03396*
X02786Y03401*
X02761Y03431D02*
X02766Y03421D01*
X02776Y03411*
X02786*
X02791Y03416*
Y03426*
X02786Y03431*
X02781*
X02776Y03426*
Y03411*
X02791Y03441D02*
Y03451D01*
Y03446*
X02761*
X02766Y03441*
X02715Y03401D02*
X0271Y03396D01*
Y03386*
X02715Y03381*
X02735*
X0274Y03386*
Y03396*
X02735Y03401*
X0271Y03431D02*
X02715Y03421D01*
X02725Y03411*
X02735*
X0274Y03416*
Y03426*
X02735Y03431*
X0273*
X02725Y03426*
Y03411*
X02715Y03441D02*
X0271Y03446D01*
Y03456*
X02715Y03461*
X02735*
X0274Y03456*
Y03446*
X02735Y03441*
X02715*
X02128Y03779D02*
X02123Y03774D01*
Y03764*
X02128Y03759*
X02148*
X02153Y03764*
Y03774*
X02148Y03779*
X02123Y03809D02*
Y03789D01*
X02138*
X02133Y03799*
Y03804*
X02138Y03809*
X02148*
X02153Y03804*
Y03794*
X02148Y03789*
Y03819D02*
X02153Y03824D01*
Y03834*
X02148Y03839*
X02128*
X02123Y03834*
Y03824*
X02128Y03819*
X02133*
X02138Y03824*
Y03839*
X02207Y03783D02*
X02202Y03778D01*
Y03768*
X02207Y03763*
X02227*
X02232Y03768*
Y03778*
X02227Y03783*
X02202Y03813D02*
Y03793D01*
X02217*
X02212Y03803*
Y03808*
X02217Y03813*
X02227*
X02232Y03808*
Y03798*
X02227Y03793*
X02207Y03823D02*
X02202Y03828D01*
Y03838*
X02207Y03843*
X02212*
X02217Y03838*
X02222Y03843*
X02227*
X02232Y03838*
Y03828*
X02227Y03823*
X02222*
X02217Y03828*
X02212Y03823*
X02207*
X02217Y03828D02*
Y03838D01*
X06571Y02946D02*
X06566Y02951D01*
X06556*
X06551Y02946*
Y02926*
X06556Y02921*
X06566*
X06571Y02926*
X06601Y02951D02*
X06581D01*
Y02936*
X06591Y02941*
X06596*
X06601Y02936*
Y02926*
X06596Y02921*
X06586*
X06581Y02926*
X06611Y02951D02*
X06631D01*
Y02946*
X06611Y02926*
Y02921*
X06327Y0308D02*
X06322Y03085D01*
X06312*
X06307Y0308*
Y0306*
X06312Y03055*
X06322*
X06327Y0306*
X06357Y03085D02*
X06337D01*
Y0307*
X06347Y03075*
X06352*
X06357Y0307*
Y0306*
X06352Y03055*
X06342*
X06337Y0306*
X06387Y03085D02*
X06377Y0308D01*
X06367Y0307*
Y0306*
X06372Y03055*
X06382*
X06387Y0306*
Y03065*
X06382Y0307*
X06367*
X04199Y03941D02*
X04194Y03936D01*
Y03926*
X04199Y03921*
X04219*
X04224Y03926*
Y03936*
X04219Y03941*
X04194Y03971D02*
Y03951D01*
X04209*
X04204Y03961*
Y03966*
X04209Y03971*
X04219*
X04224Y03966*
Y03956*
X04219Y03951*
X04194Y04001D02*
Y03981D01*
X04209*
X04204Y03991*
Y03996*
X04209Y04001*
X04219*
X04224Y03996*
Y03986*
X04219Y03981*
X04148Y03941D02*
X04143Y03936D01*
Y03926*
X04148Y03921*
X04168*
X04173Y03926*
Y03936*
X04168Y03941*
X04143Y03971D02*
Y03951D01*
X04158*
X04153Y03961*
Y03966*
X04158Y03971*
X04168*
X04173Y03966*
Y03956*
X04168Y03951*
X04173Y03996D02*
X04143D01*
X04158Y03981*
Y04001*
X06051Y02439D02*
X06046Y02434D01*
Y02424*
X06051Y02419*
X06071*
X06076Y02424*
Y02434*
X06071Y02439*
X06076Y02469D02*
Y02449D01*
X06056Y02469*
X06051*
X06046Y02464*
Y02454*
X06051Y02449*
X06076Y02499D02*
Y02479D01*
X06056Y02499*
X06051*
X06046Y02494*
Y02484*
X06051Y02479*
X05972Y02178D02*
X05967Y02183D01*
X05957*
X05952Y02178*
Y02158*
X05957Y02153*
X05967*
X05972Y02158*
X06002Y02153D02*
X05982D01*
X06002Y02173*
Y02178*
X05997Y02183*
X05987*
X05982Y02178*
X06012Y02153D02*
X06022D01*
X06017*
Y02183*
X06012Y02178*
X06924Y01978D02*
X06919Y01973D01*
Y01963*
X06924Y01958*
X06944*
X06949Y01963*
Y01973*
X06944Y01978*
X06949Y02008D02*
Y01988D01*
X06929Y02008*
X06924*
X06919Y02003*
Y01993*
X06924Y01988*
Y02018D02*
X06919Y02023D01*
Y02033*
X06924Y02038*
X06944*
X06949Y02033*
Y02023*
X06944Y02018*
X06924*
X06853Y02169D02*
X06848Y02174D01*
X06838*
X06833Y02169*
Y02149*
X06838Y02144*
X06848*
X06853Y02149*
X06863Y02144D02*
X06873D01*
X06868*
Y02174*
X06863Y02169*
X06888Y02149D02*
X06893Y02144D01*
X06903*
X06908Y02149*
Y02169*
X06903Y02174*
X06893*
X06888Y02169*
Y02164*
X06893Y02159*
X06908*
X06748Y01769D02*
X06743Y01774D01*
X06733*
X06728Y01769*
Y01749*
X06733Y01744*
X06743*
X06748Y01749*
X06758Y01744D02*
X06768D01*
X06763*
Y01774*
X06758Y01769*
X06783D02*
X06788Y01774D01*
X06798*
X06803Y01769*
Y01764*
X06798Y01759*
X06803Y01754*
Y01749*
X06798Y01744*
X06788*
X06783Y01749*
Y01754*
X06788Y01759*
X06783Y01764*
Y01769*
X06788Y01759D02*
X06798D01*
X06748Y01721D02*
X06743Y01726D01*
X06733*
X06728Y01721*
Y01701*
X06733Y01696*
X06743*
X06748Y01701*
X06758Y01696D02*
X06768D01*
X06763*
Y01726*
X06758Y01721*
X06783Y01726D02*
X06803D01*
Y01721*
X06783Y01701*
Y01696*
X06748Y01674D02*
X06743Y01679D01*
X06733*
X06728Y01674*
Y01654*
X06733Y01649*
X06743*
X06748Y01654*
X06758Y01649D02*
X06768D01*
X06763*
Y01679*
X06758Y01674*
X06803Y01679D02*
X06793Y01674D01*
X06783Y01664*
Y01654*
X06788Y01649*
X06798*
X06803Y01654*
Y01659*
X06798Y01664*
X06783*
X06748Y01623D02*
X06743Y01628D01*
X06733*
X06728Y01623*
Y01603*
X06733Y01598*
X06743*
X06748Y01603*
X06758Y01598D02*
X06768D01*
X06763*
Y01628*
X06758Y01623*
X06803Y01628D02*
X06783D01*
Y01613*
X06793Y01618*
X06798*
X06803Y01613*
Y01603*
X06798Y01598*
X06788*
X06783Y01603*
X06762Y01496D02*
X06757Y01501D01*
X06747*
X06742Y01496*
Y01476*
X06747Y01471*
X06757*
X06762Y01476*
X06772Y01471D02*
X06782D01*
X06777*
Y01501*
X06772Y01496*
X06812Y01471D02*
Y01501D01*
X06797Y01486*
X06817*
X06761Y01422D02*
X06756Y01427D01*
X06746*
X06741Y01422*
Y01402*
X06746Y01397*
X06756*
X06761Y01402*
X06771Y01397D02*
X06781D01*
X06776*
Y01427*
X06771Y01422*
X06796D02*
X06801Y01427D01*
X06811*
X06816Y01422*
Y01417*
X06811Y01412*
X06806*
X06811*
X06816Y01407*
Y01402*
X06811Y01397*
X06801*
X06796Y01402*
X06197Y02706D02*
X06192Y02711D01*
X06182*
X06177Y02706*
Y02686*
X06182Y02681*
X06192*
X06197Y02686*
X06207Y02681D02*
X06217D01*
X06212*
Y02711*
X06207Y02706*
X06252Y02681D02*
X06232D01*
X06252Y02701*
Y02706*
X06247Y02711*
X06237*
X06232Y02706*
X06201Y02658D02*
X06196Y02663D01*
X06186*
X06181Y02658*
Y02638*
X06186Y02633*
X06196*
X06201Y02638*
X06211Y02633D02*
X06221D01*
X06216*
Y02663*
X06211Y02658*
X06236Y02633D02*
X06246D01*
X06241*
Y02663*
X06236Y02658*
X06201Y02603D02*
X06196Y02608D01*
X06186*
X06181Y02603*
Y02583*
X06186Y02578*
X06196*
X06201Y02583*
X06211Y02578D02*
X06221D01*
X06216*
Y02608*
X06211Y02603*
X06236D02*
X06241Y02608D01*
X06251*
X06256Y02603*
Y02583*
X06251Y02578*
X06241*
X06236Y02583*
Y02603*
X06197Y02749D02*
X06192Y02754D01*
X06182*
X06177Y02749*
Y02729*
X06182Y02724*
X06192*
X06197Y02729*
X06207D02*
X06212Y02724D01*
X06222*
X06227Y02729*
Y02749*
X06222Y02754*
X06212*
X06207Y02749*
Y02744*
X06212Y02739*
X06227*
X06349Y02996D02*
X06344Y02991D01*
Y02981*
X06349Y02976*
X06369*
X06374Y02981*
Y02991*
X06369Y02996*
X06349Y03006D02*
X06344Y03011D01*
Y03021*
X06349Y03026*
X06354*
X06359Y03021*
X06364Y03026*
X06369*
X06374Y03021*
Y03011*
X06369Y03006*
X06364*
X06359Y03011*
X06354Y03006*
X06349*
X06359Y03011D02*
Y03021D01*
X06262Y02996D02*
X06257Y02991D01*
Y02981*
X06262Y02976*
X06282*
X06287Y02981*
Y02991*
X06282Y02996*
X06257Y03006D02*
Y03026D01*
X06262*
X06282Y03006*
X06287*
X0665Y02231D02*
X06645Y02226D01*
Y02216*
X0665Y02211*
X0667*
X06675Y02216*
Y02226*
X0667Y02231*
X06645Y02261D02*
X0665Y02251D01*
X0666Y02241*
X0667*
X06675Y02246*
Y02256*
X0667Y02261*
X06665*
X0666Y02256*
Y02241*
X06325Y02031D02*
X0632Y02026D01*
Y02016*
X06325Y02011*
X06345*
X0635Y02016*
Y02026*
X06345Y02031*
X0632Y02061D02*
Y02041D01*
X06335*
X0633Y02051*
Y02056*
X06335Y02061*
X06345*
X0635Y02056*
Y02046*
X06345Y02041*
X06505Y02085D02*
X065Y0208D01*
Y0207*
X06505Y02065*
X06525*
X0653Y0207*
Y0208*
X06525Y02085*
X0653Y0211D02*
X065D01*
X06515Y02095*
Y02115*
X06461Y02166D02*
X06456Y02161D01*
Y02151*
X06461Y02146*
X06481*
X06486Y02151*
Y02161*
X06481Y02166*
X06461Y02176D02*
X06456Y02181D01*
Y02191*
X06461Y02196*
X06466*
X06471Y02191*
Y02186*
Y02191*
X06476Y02196*
X06481*
X06486Y02191*
Y02181*
X06481Y02176*
X05678Y0345D02*
X05683Y03445D01*
X05693*
X05698Y0345*
Y0347*
X05693Y03475*
X05683*
X05678Y0347*
X05648Y03475D02*
X05668D01*
X05648Y03455*
Y0345*
X05653Y03445*
X05663*
X05668Y0345*
X05764Y0327D02*
X05759Y03275D01*
X05749*
X05744Y0327*
Y0325*
X05749Y03245*
X05759*
X05764Y0325*
X05774Y03245D02*
X05784D01*
X05779*
Y03275*
X05774Y0327*
G54D25*
X06557Y03151D03*
M02*